FILE_TYPE = MACRO_DRAWING;
SET COLOR_WIRE YELLOW;
SET COLOR_PROP ORANGE;
SET COLOR_DOT WHITE;
SET COLOR_ARC YELLOW;
SET COLOR_BODY GREEN;
SET COLOR_NOTE PURPLE;
SET PROP_DISPLAY VALUE;
SET PAGE_NUMBER P197;
FORCEADD OFFPAGE..2
(1675 8375);
FORCEPROP 2 LAST $XR0 206 
J 0
(1864 8375);
DISPLAY 0.638298 (1864 8375);
PAINT MONO (1864 8375);
FORCEPROP 2 LAST PATH I100
J 0
(1850 8450);
DISPLAY 1.021277 (1850 8450);
DISPLAY INVISIBLE (1850 8450);
FORCEPROP 1 LAST OFFPAGE TRUE
J 0
(2000 8250);
DISPLAY 0.872340 (2000 8250);
PAINT GREEN (2000 8250);
DISPLAY INVISIBLE (2000 8250);
FORCEPROP 1 LAST COMMENT_BODY TRUE
J 0
(1630 8280);
DISPLAY 0.872340 (1630 8280);
PAINT GREEN (1630 8280);
DISPLAY INVISIBLE (1630 8280);
FORCEPROP 2 LAST CDS_LIB standard
J 0
(1675 8375);
PAINT MONO (1675 8375);
DISPLAY INVISIBLE (1675 8375);
FORCEADD OFFPAGE..2
(1675 7725);
FORCEPROP 2 LAST $XR0 209 
J 0
(1864 7725);
DISPLAY 0.638298 (1864 7725);
PAINT MONO (1864 7725);
FORCEPROP 2 LAST CDS_LIB standard
J 0
(1675 7725);
PAINT MONO (1675 7725);
DISPLAY INVISIBLE (1675 7725);
FORCEPROP 2 LAST PATH I112
J 0
(1850 7800);
DISPLAY 1.021277 (1850 7800);
DISPLAY INVISIBLE (1850 7800);
FORCEPROP 1 LAST OFFPAGE TRUE
J 0
(2000 7600);
DISPLAY 0.872340 (2000 7600);
PAINT GREEN (2000 7600);
DISPLAY INVISIBLE (2000 7600);
FORCEPROP 1 LAST COMMENT_BODY TRUE
J 0
(1630 7630);
DISPLAY 0.872340 (1630 7630);
PAINT GREEN (1630 7630);
DISPLAY INVISIBLE (1630 7630);
FORCEADD OFFPAGE..2
(1675 7625);
FORCEPROP 2 LAST $XR0 209 
J 0
(1864 7625);
DISPLAY 0.638298 (1864 7625);
PAINT MONO (1864 7625);
FORCEPROP 2 LAST CDS_LIB standard
J 0
(1675 7625);
PAINT MONO (1675 7625);
DISPLAY INVISIBLE (1675 7625);
FORCEPROP 2 LAST PATH I113
J 0
(1850 7700);
DISPLAY 1.021277 (1850 7700);
DISPLAY INVISIBLE (1850 7700);
FORCEPROP 1 LAST OFFPAGE TRUE
J 0
(2000 7500);
DISPLAY 0.872340 (2000 7500);
PAINT GREEN (2000 7500);
DISPLAY INVISIBLE (2000 7500);
FORCEPROP 1 LAST COMMENT_BODY TRUE
J 0
(1630 7530);
DISPLAY 0.872340 (1630 7530);
PAINT GREEN (1630 7530);
DISPLAY INVISIBLE (1630 7530);
FORCEADD OFFPAGE..2
(1675 7675);
FORCEPROP 2 LAST $XR0 209 
J 0
(1864 7675);
DISPLAY 0.638298 (1864 7675);
PAINT MONO (1864 7675);
FORCEPROP 2 LAST CDS_LIB standard
J 0
(1675 7675);
PAINT MONO (1675 7675);
DISPLAY INVISIBLE (1675 7675);
FORCEPROP 2 LAST PATH I115
J 0
(1850 7750);
DISPLAY 1.021277 (1850 7750);
DISPLAY INVISIBLE (1850 7750);
FORCEPROP 1 LAST OFFPAGE TRUE
J 0
(2000 7550);
DISPLAY 0.872340 (2000 7550);
PAINT GREEN (2000 7550);
DISPLAY INVISIBLE (2000 7550);
FORCEPROP 1 LAST COMMENT_BODY TRUE
J 0
(1630 7580);
DISPLAY 0.872340 (1630 7580);
PAINT GREEN (1630 7580);
DISPLAY INVISIBLE (1630 7580);
FORCEADD OFFPAGE..2
(1675 7575);
FORCEPROP 2 LAST $XR0 209 
J 0
(1864 7575);
DISPLAY 0.638298 (1864 7575);
PAINT MONO (1864 7575);
FORCEPROP 2 LAST CDS_LIB standard
J 0
(1675 7575);
PAINT MONO (1675 7575);
DISPLAY INVISIBLE (1675 7575);
FORCEPROP 2 LAST PATH I116
J 0
(1850 7650);
DISPLAY 1.021277 (1850 7650);
DISPLAY INVISIBLE (1850 7650);
FORCEPROP 1 LAST OFFPAGE TRUE
J 0
(2000 7450);
DISPLAY 0.872340 (2000 7450);
PAINT GREEN (2000 7450);
DISPLAY INVISIBLE (2000 7450);
FORCEPROP 1 LAST COMMENT_BODY TRUE
J 0
(1630 7480);
DISPLAY 0.872340 (1630 7480);
PAINT GREEN (1630 7480);
DISPLAY INVISIBLE (1630 7480);
FORCEADD OFFPAGE..2
(1675 7525);
FORCEPROP 2 LAST $XR0 209 
J 0
(1864 7525);
DISPLAY 0.638298 (1864 7525);
PAINT MONO (1864 7525);
FORCEPROP 2 LAST PATH I119
J 0
(1850 7600);
DISPLAY 1.021277 (1850 7600);
DISPLAY INVISIBLE (1850 7600);
FORCEPROP 1 LAST OFFPAGE TRUE
J 0
(2000 7400);
DISPLAY 0.872340 (2000 7400);
PAINT GREEN (2000 7400);
DISPLAY INVISIBLE (2000 7400);
FORCEPROP 1 LAST COMMENT_BODY TRUE
J 0
(1630 7430);
DISPLAY 0.872340 (1630 7430);
PAINT GREEN (1630 7430);
DISPLAY INVISIBLE (1630 7430);
FORCEPROP 2 LAST CDS_LIB standard
J 0
(1675 7525);
PAINT MONO (1675 7525);
DISPLAY INVISIBLE (1675 7525);
FORCEADD OFFPAGE..2
(1675 7475);
FORCEPROP 2 LAST $XR0 209 
J 0
(1864 7475);
DISPLAY 0.638298 (1864 7475);
PAINT MONO (1864 7475);
FORCEPROP 2 LAST PATH I120
J 0
(1850 7550);
DISPLAY 1.021277 (1850 7550);
DISPLAY INVISIBLE (1850 7550);
FORCEPROP 2 LAST CDS_LIB standard
J 0
(1675 7475);
PAINT MONO (1675 7475);
DISPLAY INVISIBLE (1675 7475);
FORCEPROP 1 LAST OFFPAGE TRUE
J 0
(2000 7350);
DISPLAY 0.872340 (2000 7350);
PAINT GREEN (2000 7350);
DISPLAY INVISIBLE (2000 7350);
FORCEPROP 1 LAST COMMENT_BODY TRUE
J 0
(1630 7380);
DISPLAY 0.872340 (1630 7380);
PAINT GREEN (1630 7380);
DISPLAY INVISIBLE (1630 7380);
FORCEADD UNIVERSAL_POWER..1
(-1725 8675);
FORCEPROP 3 LASTPIN (-1725 8625) SIG_NAME P3V3_AUX_CLK_GEN_VDDA100M_CK440\g
J 0
(-1715 8635);
DISPLAY 0.659574 (-1715 8635);
PAINT MONO (-1715 8635);
DISPLAY INVISIBLE (-1715 8635);
FORCEPROP 1 LAST HDL_POWER P3V3_AUX_CLK_GEN_VDDA100M_CK440
J 1
(-1725 8725);
DISPLAY 0.553191 (-1725 8725);
PAINT GREEN (-1725 8725);
FORCEPROP 1 LAST PATH I157
J 0
(-1675 8700);
DISPLAY 0.872340 (-1675 8700);
PAINT AQUA (-1675 8700);
DISPLAY INVISIBLE (-1675 8700);
FORCEPROP 2 LAST CDS_LIB logical_power
J 0
(-1725 8675);
PAINT MONO (-1725 8675);
DISPLAY INVISIBLE (-1725 8675);
FORCEADD UNIVERSAL_POWER..1
(-2175 8800);
FORCEPROP 3 LASTPIN (-2175 8750) SIG_NAME P3V3_AUX_CLK_GEN_VDDA25M_CK440\g
J 0
(-2165 8760);
DISPLAY 0.659574 (-2165 8760);
PAINT MONO (-2165 8760);
DISPLAY INVISIBLE (-2165 8760);
FORCEPROP 1 LAST HDL_POWER P3V3_AUX_CLK_GEN_VDDA25M_CK440
J 1
(-2175 8850);
DISPLAY 0.553191 (-2175 8850);
PAINT GREEN (-2175 8850);
FORCEPROP 1 LAST PATH I158
J 0
(-2125 8825);
DISPLAY 0.872340 (-2125 8825);
PAINT AQUA (-2125 8825);
DISPLAY INVISIBLE (-2125 8825);
FORCEPROP 2 LAST CDS_LIB logical_power
J 0
(-2175 8800);
PAINT MONO (-2175 8800);
DISPLAY INVISIBLE (-2175 8800);
FORCEADD UNIVERSAL_POWER..1
(-1325 8550);
FORCEPROP 3 LASTPIN (-1325 8500) SIG_NAME P3V3_AUX_CLK_GEN_VDD_CK440\g
J 0
(-1315 8510);
DISPLAY 0.659574 (-1315 8510);
PAINT MONO (-1315 8510);
DISPLAY INVISIBLE (-1315 8510);
FORCEPROP 1 LAST HDL_POWER P3V3_AUX_CLK_GEN_VDD_CK440
J 1
(-1325 8600);
DISPLAY 0.553191 (-1325 8600);
PAINT GREEN (-1325 8600);
FORCEPROP 2 LAST CDS_LIB logical_power
J 0
(-1325 8550);
PAINT MONO (-1325 8550);
DISPLAY INVISIBLE (-1325 8550);
FORCEPROP 1 LAST PATH I159
J 0
(-1275 8575);
DISPLAY 0.872340 (-1275 8575);
PAINT AQUA (-1275 8575);
DISPLAY INVISIBLE (-1275 8575);
FORCEADD UNIVERSAL_POWER..1
(-2625 8950);
FORCEPROP 3 LASTPIN (-2625 8900) SIG_NAME P3V3_AUX_CLK_GEN_VDDMXCK_CK440\g
J 0
(-2615 8910);
DISPLAY 0.659574 (-2615 8910);
PAINT MONO (-2615 8910);
DISPLAY INVISIBLE (-2615 8910);
FORCEPROP 1 LAST HDL_POWER P3V3_AUX_CLK_GEN_VDDMXCK_CK440
J 1
(-2625 9000);
DISPLAY 0.553191 (-2625 9000);
PAINT GREEN (-2625 9000);
FORCEPROP 1 LAST PATH I160
J 0
(-2575 8975);
DISPLAY 0.872340 (-2575 8975);
PAINT AQUA (-2575 8975);
DISPLAY INVISIBLE (-2575 8975);
FORCEPROP 2 LAST CDS_LIB logical_power
J 0
(-2625 8950);
PAINT MONO (-2625 8950);
DISPLAY INVISIBLE (-2625 8950);
FORCEADD UNIVERSAL_POWER..1
(-3050 9100);
FORCEPROP 3 LASTPIN (-3050 9050) SIG_NAME P3V3_AUX_CLK_GEN_VDDPT_CK440\g
J 0
(-3040 9060);
DISPLAY 0.659574 (-3040 9060);
PAINT MONO (-3040 9060);
DISPLAY INVISIBLE (-3040 9060);
FORCEPROP 1 LAST HDL_POWER P3V3_AUX_CLK_GEN_VDDPT_CK440
J 1
(-3050 9150);
DISPLAY 0.553191 (-3050 9150);
PAINT GREEN (-3050 9150);
FORCEPROP 2 LAST CDS_LIB logical_power
J 0
(-3050 9100);
PAINT MONO (-3050 9100);
DISPLAY INVISIBLE (-3050 9100);
FORCEPROP 1 LAST PATH I161
J 0
(-3000 9125);
DISPLAY 0.872340 (-3000 9125);
PAINT AQUA (-3000 9125);
DISPLAY INVISIBLE (-3000 9125);
FORCEADD UNIVERSAL_POWER..1
(-3475 9250);
FORCEPROP 3 LASTPIN (-3475 9200) SIG_NAME P3V3_AUX_CLK_GEN_VDDXTAL_CK440\g
J 0
(-3465 9210);
DISPLAY 0.659574 (-3465 9210);
PAINT MONO (-3465 9210);
DISPLAY INVISIBLE (-3465 9210);
FORCEPROP 1 LAST HDL_POWER P3V3_AUX_CLK_GEN_VDDXTAL_CK440
J 1
(-3475 9300);
DISPLAY 0.553191 (-3475 9300);
PAINT GREEN (-3475 9300);
FORCEPROP 1 LAST PATH I162
J 0
(-3425 9275);
DISPLAY 0.872340 (-3425 9275);
PAINT AQUA (-3425 9275);
DISPLAY INVISIBLE (-3425 9275);
FORCEPROP 2 LAST CDS_LIB logical_power
J 0
(-3475 9250);
PAINT MONO (-3475 9250);
DISPLAY INVISIBLE (-3475 9250);
FORCEADD OFFPAGE..1
(-2100 7675);
FORCEPROP 2 LAST $XR0 208 
J 0
(-2352 7675);
DISPLAY 0.638298 (-2352 7675);
PAINT MONO (-2352 7675);
FORCEPROP 2 LAST PATH I163
J 0
(-2400 7725);
DISPLAY 1.021277 (-2400 7725);
DISPLAY INVISIBLE (-2400 7725);
FORCEPROP 2 LAST CDS_LIB standard
J 0
(-2100 7675);
PAINT MONO (-2100 7675);
DISPLAY INVISIBLE (-2100 7675);
FORCEPROP 1 LAST OFFPAGE TRUE
J 0
(-1775 7550);
DISPLAY 0.872340 (-1775 7550);
PAINT GREEN (-1775 7550);
DISPLAY INVISIBLE (-1775 7550);
FORCEPROP 1 LAST COMMENT_BODY TRUE
J 0
(-1975 7575);
DISPLAY 0.872340 (-1975 7575);
PAINT GREEN (-1975 7575);
DISPLAY INVISIBLE (-1975 7575);
FORCEADD OFFPAGE..1
(-2100 7575);
FORCEPROP 2 LAST $XR0 208 
J 0
(-2352 7575);
DISPLAY 0.638298 (-2352 7575);
PAINT MONO (-2352 7575);
FORCEPROP 2 LAST PATH I164
J 0
(-2400 7625);
DISPLAY 1.021277 (-2400 7625);
DISPLAY INVISIBLE (-2400 7625);
FORCEPROP 2 LAST CDS_LIB standard
J 0
(-2100 7575);
PAINT MONO (-2100 7575);
DISPLAY INVISIBLE (-2100 7575);
FORCEPROP 1 LAST OFFPAGE TRUE
J 0
(-1775 7450);
DISPLAY 0.872340 (-1775 7450);
PAINT GREEN (-1775 7450);
DISPLAY INVISIBLE (-1775 7450);
FORCEPROP 1 LAST COMMENT_BODY TRUE
J 0
(-1975 7475);
DISPLAY 0.872340 (-1975 7475);
PAINT GREEN (-1975 7475);
DISPLAY INVISIBLE (-1975 7475);
FORCEADD OFFPAGE..1
(-2100 7525);
FORCEPROP 2 LAST $XR0 208 
J 0
(-2352 7525);
DISPLAY 0.638298 (-2352 7525);
PAINT MONO (-2352 7525);
FORCEPROP 2 LAST PATH I165
J 0
(-2400 7575);
DISPLAY 1.021277 (-2400 7575);
DISPLAY INVISIBLE (-2400 7575);
FORCEPROP 2 LAST CDS_LIB standard
J 0
(-2100 7525);
PAINT MONO (-2100 7525);
DISPLAY INVISIBLE (-2100 7525);
FORCEPROP 1 LAST OFFPAGE TRUE
J 0
(-1775 7400);
DISPLAY 0.872340 (-1775 7400);
PAINT GREEN (-1775 7400);
DISPLAY INVISIBLE (-1775 7400);
FORCEPROP 1 LAST COMMENT_BODY TRUE
J 0
(-1975 7425);
DISPLAY 0.872340 (-1975 7425);
PAINT GREEN (-1975 7425);
DISPLAY INVISIBLE (-1975 7425);
FORCEADD OFFPAGE..1
(-2100 7325);
FORCEPROP 2 LAST $XR0 241 
J 0
(-2352 7325);
DISPLAY 0.638298 (-2352 7325);
PAINT MONO (-2352 7325);
FORCEPROP 2 LAST PATH I167
J 0
(-2400 7375);
DISPLAY 1.021277 (-2400 7375);
DISPLAY INVISIBLE (-2400 7375);
FORCEPROP 2 LAST CDS_LIB standard
J 0
(-2100 7325);
PAINT MONO (-2100 7325);
DISPLAY INVISIBLE (-2100 7325);
FORCEPROP 1 LAST OFFPAGE TRUE
J 0
(-1775 7200);
DISPLAY 0.872340 (-1775 7200);
PAINT GREEN (-1775 7200);
DISPLAY INVISIBLE (-1775 7200);
FORCEPROP 1 LAST COMMENT_BODY TRUE
J 0
(-1975 7225);
DISPLAY 0.872340 (-1975 7225);
PAINT GREEN (-1975 7225);
DISPLAY INVISIBLE (-1975 7225);
FORCEADD OFFPAGE..1
(-2100 7425);
FORCEPROP 2 LAST $XR0 208 
J 0
(-2352 7425);
DISPLAY 0.638298 (-2352 7425);
PAINT MONO (-2352 7425);
FORCEPROP 2 LAST PATH I168
J 0
(-2400 7475);
DISPLAY 1.021277 (-2400 7475);
DISPLAY INVISIBLE (-2400 7475);
FORCEPROP 1 LAST COMMENT_BODY TRUE
J 0
(-1975 7325);
DISPLAY 0.872340 (-1975 7325);
PAINT GREEN (-1975 7325);
DISPLAY INVISIBLE (-1975 7325);
FORCEPROP 1 LAST OFFPAGE TRUE
J 0
(-1775 7300);
DISPLAY 0.872340 (-1775 7300);
PAINT GREEN (-1775 7300);
DISPLAY INVISIBLE (-1775 7300);
FORCEPROP 2 LAST CDS_LIB standard
J 0
(-2100 7425);
PAINT MONO (-2100 7425);
DISPLAY INVISIBLE (-2100 7425);
FORCEADD OFFPAGE..1
(-2100 7075);
FORCEPROP 2 LAST $XR0 208 
J 0
(-2352 7075);
DISPLAY 0.638298 (-2352 7075);
PAINT MONO (-2352 7075);
FORCEPROP 2 LAST PATH I170
J 0
(-2400 7125);
DISPLAY 1.021277 (-2400 7125);
DISPLAY INVISIBLE (-2400 7125);
FORCEPROP 2 LAST CDS_LIB standard
J 0
(-2100 7075);
PAINT MONO (-2100 7075);
DISPLAY INVISIBLE (-2100 7075);
FORCEPROP 1 LAST OFFPAGE TRUE
J 0
(-1775 6950);
DISPLAY 0.872340 (-1775 6950);
PAINT GREEN (-1775 6950);
DISPLAY INVISIBLE (-1775 6950);
FORCEPROP 1 LAST COMMENT_BODY TRUE
J 0
(-1975 6975);
DISPLAY 0.872340 (-1975 6975);
PAINT GREEN (-1975 6975);
DISPLAY INVISIBLE (-1975 6975);
FORCEADD OFFPAGE..1
(-2100 7125);
FORCEPROP 2 LAST $XR0 208 
J 0
(-2352 7125);
DISPLAY 0.638298 (-2352 7125);
PAINT MONO (-2352 7125);
FORCEPROP 2 LAST PATH I171
J 0
(-2400 7175);
DISPLAY 1.021277 (-2400 7175);
DISPLAY INVISIBLE (-2400 7175);
FORCEPROP 2 LAST CDS_LIB standard
J 0
(-2100 7125);
PAINT MONO (-2100 7125);
DISPLAY INVISIBLE (-2100 7125);
FORCEPROP 1 LAST OFFPAGE TRUE
J 0
(-1775 7000);
DISPLAY 0.872340 (-1775 7000);
PAINT GREEN (-1775 7000);
DISPLAY INVISIBLE (-1775 7000);
FORCEPROP 1 LAST COMMENT_BODY TRUE
J 0
(-1975 7025);
DISPLAY 0.872340 (-1975 7025);
PAINT GREEN (-1975 7025);
DISPLAY INVISIBLE (-1975 7025);
FORCEADD OFFPAGE..1
(-2100 7175);
FORCEPROP 2 LAST $XR0 208 
J 0
(-2352 7175);
DISPLAY 0.638298 (-2352 7175);
PAINT MONO (-2352 7175);
FORCEPROP 2 LAST PATH I172
J 0
(-2400 7225);
DISPLAY 1.021277 (-2400 7225);
DISPLAY INVISIBLE (-2400 7225);
FORCEPROP 2 LAST CDS_LIB standard
J 0
(-2100 7175);
PAINT MONO (-2100 7175);
DISPLAY INVISIBLE (-2100 7175);
FORCEPROP 1 LAST OFFPAGE TRUE
J 0
(-1775 7050);
DISPLAY 0.872340 (-1775 7050);
PAINT GREEN (-1775 7050);
DISPLAY INVISIBLE (-1775 7050);
FORCEPROP 1 LAST COMMENT_BODY TRUE
J 0
(-1975 7075);
DISPLAY 0.872340 (-1975 7075);
PAINT GREEN (-1975 7075);
DISPLAY INVISIBLE (-1975 7075);
FORCEADD 9SQ440NQQI8..1
(-300 7325);
FORCEPROP 1 LAST PART_NUMBER AJ004400000
J 0
(-950 8725);
DISPLAY 0.723404 (-950 8725);
PAINT GREEN (-950 8725);
DISPLAY INVISIBLE (-950 8725);
FORCEPROP 2 LAST PART_TYPE SMLF
J 0
(-950 8900);
DISPLAY 1.021277 (-950 8900);
FORCEPROP 1 LAST MATERIAL IC
J 0
(-950 8650);
DISPLAY 0.723404 (-950 8650);
PAINT GREEN (-950 8650);
FORCEPROP 2 LAST VALUE 9SQ440NQQI8
J 0
(-950 8850);
DISPLAY 1.021277 (-950 8850);
FORCEPROP 1 LAST $LOCATION U13
J 0
(-950 8800);
DISPLAY 0.723404 (-950 8800);
PAINT GREEN (-950 8800);
FORCEPROP 2 LASTPIN (500 7725) $PN A5
J 0
(510 7735);
DISPLAY 0.808511 (510 7735);
FORCEPROP 2 LASTPIN (500 7675) $PN A4
J 0
(510 7685);
DISPLAY 0.808511 (510 7685);
FORCEPROP 2 LASTPIN (500 7625) $PN A3
J 0
(510 7635);
DISPLAY 0.808511 (510 7635);
FORCEPROP 2 LASTPIN (500 7575) $PN A2
J 0
(510 7585);
DISPLAY 0.808511 (510 7585);
FORCEPROP 2 LASTPIN (500 7525) $PN A56
J 0
(510 7535);
DISPLAY 0.808511 (510 7535);
FORCEPROP 2 LASTPIN (500 7475) $PN A55
J 0
(510 7485);
DISPLAY 0.808511 (510 7485);
FORCEPROP 2 LASTPIN (-1100 6125) $PN A1
J 2
(-1110 6135);
DISPLAY 0.808511 (-1110 6135);
FORCEPROP 2 LASTPIN (500 8425) $PN A34
J 0
(510 8435);
DISPLAY 0.808511 (510 8435);
FORCEPROP 2 LASTPIN (500 8375) $PN A33
J 0
(510 8385);
DISPLAY 0.808511 (510 8385);
FORCEPROP 2 LASTPIN (500 8325) $PN A32
J 0
(510 8335);
DISPLAY 0.808511 (510 8335);
FORCEPROP 2 LASTPIN (500 8275) $PN A31
J 0
(510 8285);
DISPLAY 0.808511 (510 8285);
FORCEPROP 2 LASTPIN (500 8225) $PN A28
J 0
(510 8235);
DISPLAY 0.808511 (510 8235);
FORCEPROP 2 LASTPIN (500 8175) $PN A27
J 0
(510 8185);
DISPLAY 0.808511 (510 8185);
FORCEPROP 2 LASTPIN (500 8125) $PN A25
J 0
(510 8135);
DISPLAY 0.808511 (510 8135);
FORCEPROP 2 LASTPIN (500 8075) $PN A24
J 0
(510 8085);
DISPLAY 0.808511 (510 8085);
FORCEPROP 2 LASTPIN (500 8025) $PN A23
J 0
(510 8035);
DISPLAY 0.808511 (510 8035);
FORCEPROP 2 LASTPIN (500 7975) $PN A22
J 0
(510 7985);
DISPLAY 0.808511 (510 7985);
FORCEPROP 2 LASTPIN (500 7925) $PN A21
J 0
(510 7935);
DISPLAY 0.808511 (510 7935);
FORCEPROP 2 LASTPIN (500 7875) $PN A20
J 0
(510 7885);
DISPLAY 0.808511 (510 7885);
FORCEPROP 2 LASTPIN (500 7825) $PN A19
J 0
(510 7835);
DISPLAY 0.808511 (510 7835);
FORCEPROP 2 LASTPIN (500 7775) $PN A18
J 0
(510 7785);
DISPLAY 0.808511 (510 7785);
FORCEPROP 2 LASTPIN (500 6125) $PN C1
J 0
(510 6135);
DISPLAY 0.808511 (510 6135);
FORCEPROP 2 LASTPIN (500 6275) $PN B10
J 0
(510 6285);
DISPLAY 0.808511 (510 6285);
FORCEPROP 2 LASTPIN (500 6225) $PN A14
J 0
(510 6235);
DISPLAY 0.808511 (510 6235);
FORCEPROP 2 LASTPIN (500 7375) $PN A52
J 0
(510 7385);
DISPLAY 0.808511 (510 7385);
FORCEPROP 2 LASTPIN (500 7325) $PN A51
J 0
(510 7335);
DISPLAY 0.808511 (510 7335);
FORCEPROP 2 LASTPIN (500 7275) $PN A50
J 0
(510 7285);
DISPLAY 0.808511 (510 7285);
FORCEPROP 2 LASTPIN (500 7225) $PN A49
J 0
(510 7235);
DISPLAY 0.808511 (510 7235);
FORCEPROP 2 LASTPIN (500 7175) $PN A48
J 0
(510 7185);
DISPLAY 0.808511 (510 7185);
FORCEPROP 2 LASTPIN (500 7125) $PN A47
J 0
(510 7135);
DISPLAY 0.808511 (510 7135);
FORCEPROP 2 LASTPIN (500 7075) $PN A46
J 0
(510 7085);
DISPLAY 0.808511 (510 7085);
FORCEPROP 2 LASTPIN (500 7025) $PN A45
J 0
(510 7035);
DISPLAY 0.808511 (510 7035);
FORCEPROP 2 LASTPIN (500 6975) $PN A44
J 0
(510 6985);
DISPLAY 0.808511 (510 6985);
FORCEPROP 2 LASTPIN (500 6925) $PN A43
J 0
(510 6935);
DISPLAY 0.808511 (510 6935);
FORCEPROP 2 LASTPIN (500 6875) $PN A42
J 0
(510 6885);
DISPLAY 0.808511 (510 6885);
FORCEPROP 2 LASTPIN (500 6825) $PN A41
J 0
(510 6835);
DISPLAY 0.808511 (510 6835);
FORCEPROP 2 LASTPIN (500 6775) $PN A40
J 0
(510 6785);
DISPLAY 0.808511 (510 6785);
FORCEPROP 2 LASTPIN (500 6725) $PN A39
J 0
(510 6735);
DISPLAY 0.808511 (510 6735);
FORCEPROP 2 LASTPIN (500 6675) $PN A38
J 0
(510 6685);
DISPLAY 0.808511 (510 6685);
FORCEPROP 2 LASTPIN (500 6625) $PN A37
J 0
(510 6635);
DISPLAY 0.808511 (510 6635);
FORCEPROP 2 LASTPIN (500 6575) $PN A36
J 0
(510 6585);
DISPLAY 0.808511 (510 6585);
FORCEPROP 2 LASTPIN (500 6525) $PN A35
J 0
(510 6535);
DISPLAY 0.808511 (510 6535);
FORCEPROP 2 LASTPIN (-1100 7675) $PN B38
J 2
(-1110 7685);
DISPLAY 0.808511 (-1110 7685);
FORCEPROP 2 LASTPIN (500 6175) $PN B12
J 0
(510 6185);
DISPLAY 0.808511 (510 6185);
FORCEPROP 2 LASTPIN (-1100 6975) $PN B27
J 2
(-1110 6985);
DISPLAY 0.808511 (-1110 6985);
FORCEPROP 2 LASTPIN (-1100 6925) $PN A30
J 2
(-1110 6935);
DISPLAY 0.808511 (-1110 6935);
FORCEPROP 2 LASTPIN (-1100 6875) $PN A29
J 2
(-1110 6885);
DISPLAY 0.808511 (-1110 6885);
FORCEPROP 2 LASTPIN (-1100 6825) $PN A26
J 2
(-1110 6835);
DISPLAY 0.808511 (-1110 6835);
FORCEPROP 2 LASTPIN (-1100 6775) $PN B19
J 2
(-1110 6785);
DISPLAY 0.808511 (-1110 6785);
FORCEPROP 2 LASTPIN (-1100 6725) $PN B15
J 2
(-1110 6735);
DISPLAY 0.808511 (-1110 6735);
FORCEPROP 2 LASTPIN (-1100 6675) $PN B14
J 2
(-1110 6685);
DISPLAY 0.808511 (-1110 6685);
FORCEPROP 2 LASTPIN (-1100 6525) $PN A8
J 2
(-1110 6535);
DISPLAY 0.808511 (-1110 6535);
FORCEPROP 2 LASTPIN (-1100 6475) $PN A9
J 2
(-1110 6485);
DISPLAY 0.808511 (-1110 6485);
FORCEPROP 2 LASTPIN (-1100 6575) $PN B4
J 2
(-1110 6585);
DISPLAY 0.808511 (-1110 6585);
FORCEPROP 2 LASTPIN (500 6425) $PN A6
J 0
(510 6435);
DISPLAY 0.808511 (510 6435);
FORCEPROP 2 LASTPIN (500 6375) $PN A7
J 0
(510 6385);
DISPLAY 0.808511 (510 6385);
FORCEPROP 2 LASTPIN (-1100 6375) $PN A17
J 2
(-1110 6385);
DISPLAY 0.808511 (-1110 6385);
FORCEPROP 2 LASTPIN (-1100 7575) $PN A54
J 2
(-1110 7585);
DISPLAY 0.808511 (-1110 7585);
FORCEPROP 2 LASTPIN (-1100 7525) $PN B43
J 2
(-1110 7535);
DISPLAY 0.808511 (-1110 7535);
FORCEPROP 2 LASTPIN (-1100 7475) $PN A53
J 2
(-1110 7485);
DISPLAY 0.808511 (-1110 7485);
FORCEPROP 2 LASTPIN (-1100 7325) $PN A10
J 2
(-1110 7335);
DISPLAY 0.808511 (-1110 7335);
FORCEPROP 2 LASTPIN (-1100 7425) $PN B42
J 2
(-1110 7435);
DISPLAY 0.808511 (-1110 7435);
FORCEPROP 2 LASTPIN (-1100 7175) $PN A11
J 2
(-1110 7185);
DISPLAY 0.808511 (-1110 7185);
FORCEPROP 2 LASTPIN (-1100 7125) $PN B9
J 2
(-1110 7135);
DISPLAY 0.808511 (-1110 7135);
FORCEPROP 2 LASTPIN (-1100 7275) $PN B8
J 2
(-1110 7285);
DISPLAY 0.808511 (-1110 7285);
FORCEPROP 2 LASTPIN (-1100 7075) $PN A16
J 2
(-1110 7085);
DISPLAY 0.808511 (-1110 7085);
FORCEPROP 2 LASTPIN (-1100 8375) $PN B21
J 2
(-1110 8385);
DISPLAY 0.808511 (-1110 8385);
FORCEPROP 2 LASTPIN (-1100 8425) $PN B23
J 2
(-1110 8435);
DISPLAY 0.808511 (-1110 8435);
FORCEPROP 2 LASTPIN (-1100 8225) $PN B1
J 2
(-1110 8235);
DISPLAY 0.808511 (-1110 8235);
FORCEPROP 2 LASTPIN (-1100 8275) $PN B17
J 2
(-1110 8285);
DISPLAY 0.808511 (-1110 8285);
FORCEPROP 2 LASTPIN (-1100 7975) $PN B29
J 2
(-1110 7985);
DISPLAY 0.808511 (-1110 7985);
FORCEPROP 2 LASTPIN (-1100 8025) $PN B32
J 2
(-1110 8035);
DISPLAY 0.808511 (-1110 8035);
FORCEPROP 2 LASTPIN (-1100 8075) $PN B35
J 2
(-1110 8085);
DISPLAY 0.808511 (-1110 8085);
FORCEPROP 2 LASTPIN (-1100 8125) $PN B40
J 2
(-1110 8135);
DISPLAY 0.808511 (-1110 8135);
FORCEPROP 2 LASTPIN (-1100 7875) $PN B6
J 2
(-1110 7885);
DISPLAY 0.808511 (-1110 7885);
FORCEPROP 2 LASTPIN (-1100 7775) $PN A12
J 2
(-1110 7785);
DISPLAY 0.808511 (-1110 7785);
FORCEPROP 2 LASTPIN (-1100 6275) $PN A13
J 2
(-1110 6285);
DISPLAY 0.808511 (-1110 6285);
FORCEPROP 2 LASTPIN (-1100 6225) $PN B11
J 2
(-1110 6235);
DISPLAY 0.808511 (-1110 6235);
FORCEPROP 1 LAST NEEDS_NO_SIZE TRUE
J 0
(-300 7325);
DISPLAY 0.723404 (-300 7325);
PAINT GREEN (-300 7325);
DISPLAY INVISIBLE (-300 7325);
FORCEPROP 1 LAST PATH I180
J 0
(-300 7325);
DISPLAY 0.723404 (-300 7325);
PAINT GREEN (-300 7325);
DISPLAY INVISIBLE (-300 7325);
FORCEPROP 2 LAST CDS_LIB pure_quanta
J 0
(-300 7325);
PAINT MONO (-300 7325);
DISPLAY INVISIBLE (-300 7325);
FORCEPROP 1 LAST CDS_LMAN_SYM_OUTLINE -650,1300,650,-1300
J 0
(-300 7325);
DISPLAY 0.468085 (-300 7325);
PAINT GREEN (-300 7325);
DISPLAY INVISIBLE (-300 7325);
FORCEPROP 2 LAST CDS_LOCATION U13
J 0
(-950 8950);
DISPLAY 1.021277 (-950 8950);
DISPLAY INVISIBLE (-950 8950);
FORCEPROP 2 LAST $SEC 1
J 0
(-950 8950);
DISPLAY 0.680851 (-950 8950);
PAINT MONO (-950 8950);
DISPLAY INVISIBLE (-950 8950);
FORCEPROP 2 LAST CDS_SEC 1
J 0
(-950 8950);
DISPLAY 1.021277 (-950 8950);
DISPLAY INVISIBLE (-950 8950);
FORCEADD OFFPAGE..1
(-2100 6375);
FORCEPROP 2 LAST $XR3 211 
J 0
(-2712 6375);
DISPLAY 0.638298 (-2712 6375);
PAINT MONO (-2712 6375);
FORCEPROP 2 LAST $XR2 206 
J 0
(-2592 6375);
DISPLAY 0.638298 (-2592 6375);
PAINT MONO (-2592 6375);
FORCEPROP 2 LAST $XR1 223 
J 0
(-2472 6375);
DISPLAY 0.638298 (-2472 6375);
PAINT MONO (-2472 6375);
FORCEPROP 2 LAST $XR0 208 
J 0
(-2352 6375);
DISPLAY 0.638298 (-2352 6375);
PAINT MONO (-2352 6375);
FORCEPROP 1 LAST OFFPAGE TRUE
J 0
(-1775 6250);
DISPLAY 0.872340 (-1775 6250);
PAINT GREEN (-1775 6250);
DISPLAY INVISIBLE (-1775 6250);
FORCEPROP 1 LAST COMMENT_BODY TRUE
J 0
(-1975 6275);
DISPLAY 0.872340 (-1975 6275);
PAINT GREEN (-1975 6275);
DISPLAY INVISIBLE (-1975 6275);
FORCEPROP 2 LAST PATH I182
J 0
(-2400 6425);
DISPLAY 1.021277 (-2400 6425);
DISPLAY INVISIBLE (-2400 6425);
FORCEPROP 2 LAST CDS_LIB standard
J 0
(-2100 6375);
PAINT MONO (-2100 6375);
DISPLAY INVISIBLE (-2100 6375);
FORCEADD OFFPAGE..2
(1675 7175);
FORCEPROP 2 LAST $XR0 209 
J 0
(1864 7175);
DISPLAY 0.638298 (1864 7175);
PAINT MONO (1864 7175);
FORCEPROP 2 LAST PATH I206
J 0
(1875 7225);
DISPLAY 1.021277 (1875 7225);
DISPLAY INVISIBLE (1875 7225);
FORCEPROP 1 LAST OFFPAGE TRUE
J 0
(2000 7050);
DISPLAY 0.872340 (2000 7050);
PAINT GREEN (2000 7050);
DISPLAY INVISIBLE (2000 7050);
FORCEPROP 1 LAST COMMENT_BODY TRUE
J 0
(1630 7080);
DISPLAY 0.872340 (1630 7080);
PAINT GREEN (1630 7080);
DISPLAY INVISIBLE (1630 7080);
FORCEPROP 2 LAST CDS_LIB standard
J 0
(1675 7175);
PAINT MONO (1675 7175);
DISPLAY INVISIBLE (1675 7175);
FORCEADD OFFPAGE..2
(1675 7125);
FORCEPROP 2 LAST $XR0 209 
J 0
(1864 7125);
DISPLAY 0.638298 (1864 7125);
PAINT MONO (1864 7125);
FORCEPROP 2 LAST CDS_LIB standard
J 0
(1675 7125);
PAINT MONO (1675 7125);
DISPLAY INVISIBLE (1675 7125);
FORCEPROP 2 LAST PATH I207
J 0
(1875 7175);
DISPLAY 1.021277 (1875 7175);
DISPLAY INVISIBLE (1875 7175);
FORCEPROP 1 LAST OFFPAGE TRUE
J 0
(2000 7000);
DISPLAY 0.872340 (2000 7000);
PAINT GREEN (2000 7000);
DISPLAY INVISIBLE (2000 7000);
FORCEPROP 1 LAST COMMENT_BODY TRUE
J 0
(1630 7030);
DISPLAY 0.872340 (1630 7030);
PAINT GREEN (1630 7030);
DISPLAY INVISIBLE (1630 7030);
FORCEADD OFFPAGE..3
R 2
(-2100 7275);
FORCEPROP 2 LAST $XR0 241 
J 0
(-2380 7275);
DISPLAY 0.638298 (-2380 7275);
PAINT MONO (-2380 7275);
FORCEPROP 2 LAST CDS_LIB standard
J 0
(-2100 7275);
PAINT MONO (-2100 7275);
DISPLAY INVISIBLE (-2100 7275);
FORCEPROP 2 LAST PATH I242
J 0
(-2425 7325);
DISPLAY 1.021277 (-2425 7325);
DISPLAY INVISIBLE (-2425 7325);
FORCEPROP 1 LAST OFFPAGE TRUE
J 2
(-2425 7150);
DISPLAY 0.872340 (-2425 7150);
DISPLAY INVISIBLE (-2425 7150);
FORCEPROP 1 LAST COMMENT_BODY TRUE
J 2
(-2050 7175);
DISPLAY 0.872340 (-2050 7175);
PAINT GREEN (-2050 7175);
DISPLAY INVISIBLE (-2050 7175);
FORCEADD Q_RES..1
(-2325 6125);
FORCEPROP 1 LAST PART_NUMBER CS00002JB13
J 0
(-2400 6075);
DISPLAY 0.319149 (-2400 6075);
DISPLAY INVISIBLE (-2400 6075);
FORCEPROP 1 LAST WATTAGE 1/16W
J 2
(-2200 6050);
DISPLAY 0.319149 (-2200 6050);
FORCEPROP 1 LAST VALUE 0
J 2
(-2175 6125);
DISPLAY 0.404255 (-2175 6125);
FORCEPROP 1 LAST MATERIAL CHIP
J 0
(-2100 6125);
DISPLAY 0.404255 (-2100 6125);
FORCEPROP 1 LAST TOLERANCE 5%
J 0
(-2150 6125);
DISPLAY 0.404255 (-2150 6125);
FORCEPROP 1 LAST PACK_TYPE 0402LF
J 0
(-2400 6050);
DISPLAY 0.319149 (-2400 6050);
FORCEPROP 1 LAST $LOCATION R1680
J 0
(-2525 6125);
DISPLAY 0.510638 (-2525 6125);
FORCEPROP 1 LASTPIN (-2425 6125) $PN 1
J 0
(-2413 6137);
DISPLAY 0.787234 (-2413 6137);
FORCEPROP 1 LASTPIN (-2225 6125) $PN 2
J 0
(-2263 6137);
DISPLAY 0.787234 (-2263 6137);
FORCEPROP 1 LAST PATH I252
J 0
(-2375 6275);
DISPLAY 0.978723 (-2375 6275);
PAINT WHITE (-2375 6275);
DISPLAY INVISIBLE (-2375 6275);
FORCEPROP 2 LAST CDS_LIB pure_quanta
J 0
(-2325 6125);
PAINT MONO (-2325 6125);
DISPLAY INVISIBLE (-2325 6125);
FORCEPROP 2 LAST CDS_LOCATION R1680
J 0
(-2375 6325);
DISPLAY 1.021277 (-2375 6325);
DISPLAY INVISIBLE (-2375 6325);
FORCEPROP 2 LAST $SEC 1
J 0
(-2375 6325);
DISPLAY 0.680851 (-2375 6325);
PAINT MONO (-2375 6325);
DISPLAY INVISIBLE (-2375 6325);
FORCEPROP 2 LAST CDS_SEC 1
J 0
(-2375 6325);
DISPLAY 1.021277 (-2375 6325);
DISPLAY INVISIBLE (-2375 6325);
FORCEADD OFFPAGE..1
(-3325 6125);
FORCEPROP 2 LAST $XR0 223 
J 0
(-3577 6125);
DISPLAY 0.638298 (-3577 6125);
PAINT MONO (-3577 6125);
FORCEPROP 2 LAST CDS_LIB standard
J 0
(-3325 6125);
PAINT MONO (-3325 6125);
DISPLAY INVISIBLE (-3325 6125);
FORCEPROP 2 LAST PATH I253
J 0
(-3600 6175);
DISPLAY 1.021277 (-3600 6175);
DISPLAY INVISIBLE (-3600 6175);
FORCEPROP 1 LAST OFFPAGE TRUE
J 0
(-3000 6000);
DISPLAY 0.872340 (-3000 6000);
PAINT GREEN (-3000 6000);
DISPLAY INVISIBLE (-3000 6000);
FORCEPROP 1 LAST COMMENT_BODY TRUE
J 0
(-3200 6025);
DISPLAY 0.872340 (-3200 6025);
PAINT GREEN (-3200 6025);
DISPLAY INVISIBLE (-3200 6025);
FORCEADD OFFPAGE..1
(-3325 6025);
FORCEPROP 2 LAST $XR0 208 
J 0
(-3577 6025);
DISPLAY 0.638298 (-3577 6025);
PAINT MONO (-3577 6025);
FORCEPROP 2 LAST CDS_LIB standard
J 0
(-3325 6025);
PAINT MONO (-3325 6025);
DISPLAY INVISIBLE (-3325 6025);
FORCEPROP 2 LAST PATH I254
J 0
(-3600 6075);
DISPLAY 1.021277 (-3600 6075);
DISPLAY INVISIBLE (-3600 6075);
FORCEPROP 1 LAST COMMENT_BODY TRUE
J 0
(-3200 5925);
DISPLAY 0.872340 (-3200 5925);
PAINT GREEN (-3200 5925);
DISPLAY INVISIBLE (-3200 5925);
FORCEPROP 1 LAST OFFPAGE TRUE
J 0
(-3000 5900);
DISPLAY 0.872340 (-3000 5900);
PAINT GREEN (-3000 5900);
DISPLAY INVISIBLE (-3000 5900);
FORCEADD OFFPAGE..2
(-2300 10175);
FORCEPROP 2 LAST $XR0 208 
J 0
(-2111 10175);
DISPLAY 0.638298 (-2111 10175);
PAINT MONO (-2111 10175);
FORCEPROP 1 LAST OFFPAGE TRUE
J 0
(-1975 10050);
DISPLAY 0.872340 (-1975 10050);
PAINT GREEN (-1975 10050);
DISPLAY INVISIBLE (-1975 10050);
FORCEPROP 1 LAST COMMENT_BODY TRUE
J 0
(-2345 10080);
DISPLAY 0.872340 (-2345 10080);
PAINT GREEN (-2345 10080);
DISPLAY INVISIBLE (-2345 10080);
FORCEPROP 2 LAST CDS_LIB standard
J 0
(-2300 10175);
PAINT MONO (-2300 10175);
DISPLAY INVISIBLE (-2300 10175);
FORCEPROP 2 LAST PATH I255
J 0
(-2100 10225);
DISPLAY 1.021277 (-2100 10225);
DISPLAY INVISIBLE (-2100 10225);
FORCEADD OFFPAGE..2
(-2300 10125);
FORCEPROP 2 LAST $XR0 208 
J 0
(-2111 10125);
DISPLAY 0.638298 (-2111 10125);
PAINT MONO (-2111 10125);
FORCEPROP 1 LAST OFFPAGE TRUE
J 0
(-1975 10000);
DISPLAY 0.872340 (-1975 10000);
PAINT GREEN (-1975 10000);
DISPLAY INVISIBLE (-1975 10000);
FORCEPROP 1 LAST COMMENT_BODY TRUE
J 0
(-2345 10030);
DISPLAY 0.872340 (-2345 10030);
PAINT GREEN (-2345 10030);
DISPLAY INVISIBLE (-2345 10030);
FORCEPROP 2 LAST CDS_LIB standard
J 0
(-2300 10125);
PAINT MONO (-2300 10125);
DISPLAY INVISIBLE (-2300 10125);
FORCEPROP 2 LAST PATH I256
J 0
(-2100 10175);
DISPLAY 1.021277 (-2100 10175);
DISPLAY INVISIBLE (-2100 10175);
FORCEADD OFFPAGE..2
(-2300 10275);
FORCEPROP 2 LAST $XR0 208 
J 0
(-2111 10275);
DISPLAY 0.638298 (-2111 10275);
PAINT MONO (-2111 10275);
FORCEPROP 1 LAST OFFPAGE TRUE
J 0
(-1975 10150);
DISPLAY 0.872340 (-1975 10150);
PAINT GREEN (-1975 10150);
DISPLAY INVISIBLE (-1975 10150);
FORCEPROP 1 LAST COMMENT_BODY TRUE
J 0
(-2345 10180);
DISPLAY 0.872340 (-2345 10180);
PAINT GREEN (-2345 10180);
DISPLAY INVISIBLE (-2345 10180);
FORCEPROP 2 LAST CDS_LIB standard
J 0
(-2300 10275);
PAINT MONO (-2300 10275);
DISPLAY INVISIBLE (-2300 10275);
FORCEPROP 2 LAST PATH I257
J 0
(-2100 10325);
DISPLAY 1.021277 (-2100 10325);
DISPLAY INVISIBLE (-2100 10325);
FORCEADD OFFPAGE..2
(-2300 10325);
FORCEPROP 2 LAST $XR0 208 
J 0
(-2111 10325);
DISPLAY 0.638298 (-2111 10325);
PAINT MONO (-2111 10325);
FORCEPROP 1 LAST OFFPAGE TRUE
J 0
(-1975 10200);
DISPLAY 0.872340 (-1975 10200);
PAINT GREEN (-1975 10200);
DISPLAY INVISIBLE (-1975 10200);
FORCEPROP 1 LAST COMMENT_BODY TRUE
J 0
(-2345 10230);
DISPLAY 0.872340 (-2345 10230);
PAINT GREEN (-2345 10230);
DISPLAY INVISIBLE (-2345 10230);
FORCEPROP 2 LAST CDS_LIB standard
J 0
(-2300 10325);
PAINT MONO (-2300 10325);
DISPLAY INVISIBLE (-2300 10325);
FORCEPROP 2 LAST PATH I258
J 0
(-2100 10375);
DISPLAY 1.021277 (-2100 10375);
DISPLAY INVISIBLE (-2100 10375);
FORCEADD OFFPAGE..2
(-2300 10375);
FORCEPROP 2 LAST $XR0 208 
J 0
(-2111 10375);
DISPLAY 0.638298 (-2111 10375);
PAINT MONO (-2111 10375);
FORCEPROP 2 LAST CDS_LIB standard
J 0
(-2300 10375);
PAINT MONO (-2300 10375);
DISPLAY INVISIBLE (-2300 10375);
FORCEPROP 1 LAST COMMENT_BODY TRUE
J 0
(-2345 10280);
DISPLAY 0.872340 (-2345 10280);
PAINT GREEN (-2345 10280);
DISPLAY INVISIBLE (-2345 10280);
FORCEPROP 1 LAST OFFPAGE TRUE
J 0
(-1975 10250);
DISPLAY 0.872340 (-1975 10250);
PAINT GREEN (-1975 10250);
DISPLAY INVISIBLE (-1975 10250);
FORCEPROP 2 LAST PATH I259
J 0
(-2100 10425);
DISPLAY 1.021277 (-2100 10425);
DISPLAY INVISIBLE (-2100 10425);
FORCEADD OFFPAGE..2
(-2300 10425);
FORCEPROP 2 LAST $XR0 208 
J 0
(-2111 10425);
DISPLAY 0.638298 (-2111 10425);
PAINT MONO (-2111 10425);
FORCEPROP 2 LAST CDS_LIB standard
J 0
(-2300 10425);
PAINT MONO (-2300 10425);
DISPLAY INVISIBLE (-2300 10425);
FORCEPROP 1 LAST COMMENT_BODY TRUE
J 0
(-2345 10330);
DISPLAY 0.872340 (-2345 10330);
PAINT GREEN (-2345 10330);
DISPLAY INVISIBLE (-2345 10330);
FORCEPROP 1 LAST OFFPAGE TRUE
J 0
(-1975 10300);
DISPLAY 0.872340 (-1975 10300);
PAINT GREEN (-1975 10300);
DISPLAY INVISIBLE (-1975 10300);
FORCEPROP 2 LAST PATH I260
J 0
(-2100 10475);
DISPLAY 1.021277 (-2100 10475);
DISPLAY INVISIBLE (-2100 10475);
FORCEADD OFFPAGE..2
(-2300 10475);
FORCEPROP 2 LAST $XR0 208 
J 0
(-2111 10475);
DISPLAY 0.638298 (-2111 10475);
PAINT MONO (-2111 10475);
FORCEPROP 2 LAST CDS_LIB standard
J 0
(-2300 10475);
PAINT MONO (-2300 10475);
DISPLAY INVISIBLE (-2300 10475);
FORCEPROP 1 LAST OFFPAGE TRUE
J 0
(-1975 10350);
DISPLAY 0.872340 (-1975 10350);
PAINT GREEN (-1975 10350);
DISPLAY INVISIBLE (-1975 10350);
FORCEPROP 1 LAST COMMENT_BODY TRUE
J 0
(-2345 10380);
DISPLAY 0.872340 (-2345 10380);
PAINT GREEN (-2345 10380);
DISPLAY INVISIBLE (-2345 10380);
FORCEPROP 2 LAST PATH I261
J 0
(-1950 10525);
DISPLAY 1.021277 (-1950 10525);
DISPLAY INVISIBLE (-1950 10525);
FORCEADD OFFPAGE..2
(-2300 10225);
FORCEPROP 2 LAST $XR3 211 
J 0
(-1751 10225);
DISPLAY 0.638298 (-1751 10225);
PAINT MONO (-1751 10225);
FORCEPROP 2 LAST $XR2 208 
J 0
(-1871 10225);
DISPLAY 0.638298 (-1871 10225);
PAINT MONO (-1871 10225);
FORCEPROP 2 LAST $XR1 206 
J 0
(-1991 10225);
DISPLAY 0.638298 (-1991 10225);
PAINT MONO (-1991 10225);
FORCEPROP 2 LAST $XR0 223 
J 0
(-2111 10225);
DISPLAY 0.638298 (-2111 10225);
PAINT MONO (-2111 10225);
FORCEPROP 1 LAST OFFPAGE TRUE
J 0
(-1975 10100);
DISPLAY 0.872340 (-1975 10100);
PAINT GREEN (-1975 10100);
DISPLAY INVISIBLE (-1975 10100);
FORCEPROP 1 LAST COMMENT_BODY TRUE
J 0
(-2345 10130);
DISPLAY 0.872340 (-2345 10130);
PAINT GREEN (-2345 10130);
DISPLAY INVISIBLE (-2345 10130);
FORCEPROP 2 LAST CDS_LIB standard
J 0
(-2300 10225);
PAINT MONO (-2300 10225);
DISPLAY INVISIBLE (-2300 10225);
FORCEPROP 2 LAST PATH I262
J 0
(-1650 10275);
DISPLAY 1.021277 (-1650 10275);
DISPLAY INVISIBLE (-1650 10275);
FORCEADD OFFPAGE..2
(-2300 10075);
FORCEPROP 2 LAST $XR0 208 
J 0
(-2111 10075);
DISPLAY 0.638298 (-2111 10075);
PAINT MONO (-2111 10075);
FORCEPROP 1 LAST OFFPAGE TRUE
J 0
(-1975 9950);
DISPLAY 0.872340 (-1975 9950);
PAINT GREEN (-1975 9950);
DISPLAY INVISIBLE (-1975 9950);
FORCEPROP 1 LAST COMMENT_BODY TRUE
J 0
(-2345 9980);
DISPLAY 0.872340 (-2345 9980);
PAINT GREEN (-2345 9980);
DISPLAY INVISIBLE (-2345 9980);
FORCEPROP 2 LAST CDS_LIB standard
J 0
(-2300 10075);
PAINT MONO (-2300 10075);
DISPLAY INVISIBLE (-2300 10075);
FORCEPROP 2 LAST PATH I263
J 0
(-2100 10125);
DISPLAY 1.021277 (-2100 10125);
DISPLAY INVISIBLE (-2100 10125);
FORCEADD OFFPAGE..2
(-2300 10025);
FORCEPROP 2 LAST $XR0 208 
J 0
(-2111 10025);
DISPLAY 0.638298 (-2111 10025);
PAINT MONO (-2111 10025);
FORCEPROP 1 LAST COMMENT_BODY TRUE
J 0
(-2345 9930);
DISPLAY 0.872340 (-2345 9930);
PAINT GREEN (-2345 9930);
DISPLAY INVISIBLE (-2345 9930);
FORCEPROP 1 LAST OFFPAGE TRUE
J 0
(-1975 9900);
DISPLAY 0.872340 (-1975 9900);
PAINT GREEN (-1975 9900);
DISPLAY INVISIBLE (-1975 9900);
FORCEPROP 2 LAST CDS_LIB standard
J 0
(-2300 10025);
PAINT MONO (-2300 10025);
DISPLAY INVISIBLE (-2300 10025);
FORCEPROP 2 LAST PATH I264
J 0
(-2100 10075);
DISPLAY 1.021277 (-2100 10075);
DISPLAY INVISIBLE (-2100 10075);
FORCEADD Q_RES..2
(-3150 10725);
FORCEPROP 1 LAST PART_NUMBER CS31002FB08
J 0
(-3110 10600);
DISPLAY 0.638298 (-3110 10600);
DISPLAY INVISIBLE (-3110 10600);
FORCEPROP 1 LAST WATTAGE 1/16W
J 0
(-3110 10700);
DISPLAY 0.638298 (-3110 10700);
FORCEPROP 1 LAST TOLERANCE 1%
J 0
(-3105 10750);
DISPLAY 0.638298 (-3105 10750);
FORCEPROP 1 LAST VALUE 10K
J 0
(-3105 10800);
DISPLAY 0.638298 (-3105 10800);
FORCEPROP 1 LAST MATERIAL EMPTY
J 0
(-3110 10650);
DISPLAY 0.638298 (-3110 10650);
PAINT RED (-3110 10650);
FORCEPROP 1 LAST PACK_TYPE 0402LF
J 0
(-3110 10600);
DISPLAY 0.638298 (-3110 10600);
FORCEPROP 1 LAST $LOCATION R1483
J 0
(-3105 10850);
DISPLAY 0.978723 (-3105 10850);
FORCEPROP 1 LASTPIN (-3150 10825) $PN 1
J 0
(-3145 10787);
DISPLAY 0.787234 (-3145 10787);
FORCEPROP 1 LASTPIN (-3150 10625) $PN 2
J 0
(-3145 10635);
DISPLAY 0.787234 (-3145 10635);
FORCEPROP 2 LAST CDS_LIB pure_quanta
J 0
(-3150 10725);
PAINT MONO (-3150 10725);
DISPLAY INVISIBLE (-3150 10725);
FORCEPROP 1 LAST PATH I265
J 0
(-3100 10900);
DISPLAY 0.978723 (-3100 10900);
PAINT WHITE (-3100 10900);
DISPLAY INVISIBLE (-3100 10900);
FORCEPROP 2 LAST CDS_LOCATION R1483
J 0
(-3100 10950);
DISPLAY 1.021277 (-3100 10950);
DISPLAY INVISIBLE (-3100 10950);
FORCEPROP 2 LAST $SEC 1
J 0
(-3100 10950);
DISPLAY 0.680851 (-3100 10950);
PAINT MONO (-3100 10950);
DISPLAY INVISIBLE (-3100 10950);
FORCEPROP 2 LAST CDS_SEC 1
J 0
(-3100 10950);
DISPLAY 1.021277 (-3100 10950);
DISPLAY INVISIBLE (-3100 10950);
FORCEADD Q_RES..2
(-3625 10725);
FORCEPROP 1 LAST PART_NUMBER CS24752FB03
J 0
(-3585 10600);
DISPLAY 0.638298 (-3585 10600);
DISPLAY INVISIBLE (-3585 10600);
FORCEPROP 1 LAST VALUE 4.75K
J 0
(-3580 10800);
DISPLAY 0.638298 (-3580 10800);
FORCEPROP 1 LAST MATERIAL CHIP
J 0
(-3585 10650);
DISPLAY 0.638298 (-3585 10650);
FORCEPROP 1 LAST WATTAGE 1/16W
J 0
(-3585 10700);
DISPLAY 0.638298 (-3585 10700);
FORCEPROP 1 LAST TOLERANCE 1%
J 0
(-3580 10750);
DISPLAY 0.638298 (-3580 10750);
FORCEPROP 1 LAST PACK_TYPE 0402LF
J 0
(-3585 10600);
DISPLAY 0.638298 (-3585 10600);
FORCEPROP 1 LAST $LOCATION R1471
J 0
(-3580 10850);
DISPLAY 0.638298 (-3580 10850);
FORCEPROP 1 LASTPIN (-3625 10825) $PN 1
J 0
(-3620 10787);
DISPLAY 0.787234 (-3620 10787);
FORCEPROP 1 LASTPIN (-3625 10625) $PN 2
J 0
(-3620 10635);
DISPLAY 0.787234 (-3620 10635);
FORCEPROP 1 LAST PATH I267
J 0
(-3575 10900);
DISPLAY 0.978723 (-3575 10900);
PAINT WHITE (-3575 10900);
DISPLAY INVISIBLE (-3575 10900);
FORCEPROP 2 LAST CDS_LIB pure_quanta
J 0
(-3625 10725);
PAINT MONO (-3625 10725);
DISPLAY INVISIBLE (-3625 10725);
FORCEPROP 2 LAST CDS_LOCATION R1471
J 0
(-3575 10950);
DISPLAY 1.021277 (-3575 10950);
DISPLAY INVISIBLE (-3575 10950);
FORCEPROP 2 LAST $SEC 1
J 0
(-3575 10950);
DISPLAY 0.680851 (-3575 10950);
PAINT MONO (-3575 10950);
DISPLAY INVISIBLE (-3575 10950);
FORCEPROP 2 LAST CDS_SEC 1
J 0
(-3575 10950);
DISPLAY 1.021277 (-3575 10950);
DISPLAY INVISIBLE (-3575 10950);
FORCEADD Q_RES..2
(-3150 9800);
FORCEPROP 1 LAST PART_NUMBER CS21002FB06
J 0
(-3110 9675);
DISPLAY 0.638298 (-3110 9675);
DISPLAY INVISIBLE (-3110 9675);
FORCEPROP 1 LAST TOLERANCE 1%
J 0
(-3105 9825);
DISPLAY 0.638298 (-3105 9825);
FORCEPROP 1 LAST MATERIAL EMPTY
J 0
(-3110 9725);
DISPLAY 0.638298 (-3110 9725);
PAINT RED (-3110 9725);
FORCEPROP 1 LAST WATTAGE 1/16W
J 0
(-3110 9775);
DISPLAY 0.638298 (-3110 9775);
FORCEPROP 1 LAST PACK_TYPE 0402LF
J 0
(-3110 9675);
DISPLAY 0.638298 (-3110 9675);
FORCEPROP 1 LAST VALUE 1K
J 0
(-3105 9875);
DISPLAY 0.638298 (-3105 9875);
FORCEPROP 1 LAST $LOCATION R1484
J 0
(-3105 9925);
DISPLAY 0.638298 (-3105 9925);
FORCEPROP 1 LASTPIN (-3150 9900) $PN 1
J 0
(-3145 9862);
DISPLAY 0.787234 (-3145 9862);
FORCEPROP 1 LASTPIN (-3150 9700) $PN 2
J 0
(-3145 9710);
DISPLAY 0.787234 (-3145 9710);
FORCEPROP 2 LAST CDS_LIB pure_quanta
J 0
(-3150 9800);
PAINT MONO (-3150 9800);
DISPLAY INVISIBLE (-3150 9800);
FORCEPROP 1 LAST PATH I268
J 0
(-3100 9975);
DISPLAY 0.978723 (-3100 9975);
PAINT WHITE (-3100 9975);
DISPLAY INVISIBLE (-3100 9975);
FORCEPROP 2 LAST CDS_LOCATION R1484
J 0
(-3100 10025);
DISPLAY 1.021277 (-3100 10025);
DISPLAY INVISIBLE (-3100 10025);
FORCEPROP 2 LAST $SEC 1
J 0
(-3100 10025);
DISPLAY 0.680851 (-3100 10025);
PAINT MONO (-3100 10025);
DISPLAY INVISIBLE (-3100 10025);
FORCEPROP 2 LAST CDS_SEC 1
J 0
(-3100 10025);
DISPLAY 1.021277 (-3100 10025);
DISPLAY INVISIBLE (-3100 10025);
FORCEADD Q_RES..2
(-3375 9800);
FORCEPROP 1 LAST PART_NUMBER CS21002FB06
J 0
(-3335 9675);
DISPLAY 0.638298 (-3335 9675);
DISPLAY INVISIBLE (-3335 9675);
FORCEPROP 1 LAST VALUE 1K
J 0
(-3330 9875);
DISPLAY 0.638298 (-3330 9875);
FORCEPROP 1 LAST TOLERANCE 1%
J 0
(-3330 9825);
DISPLAY 0.638298 (-3330 9825);
FORCEPROP 1 LAST WATTAGE 1/16W
J 0
(-3335 9775);
DISPLAY 0.638298 (-3335 9775);
FORCEPROP 1 LAST MATERIAL CHIP
J 0
(-3335 9725);
DISPLAY 0.638298 (-3335 9725);
FORCEPROP 1 LAST PACK_TYPE 0402LF
J 0
(-3335 9675);
DISPLAY 0.638298 (-3335 9675);
FORCEPROP 1 LAST $LOCATION R1527
J 0
(-3330 9925);
DISPLAY 0.638298 (-3330 9925);
FORCEPROP 1 LASTPIN (-3375 9900) $PN 1
J 0
(-3370 9862);
DISPLAY 0.787234 (-3370 9862);
FORCEPROP 1 LASTPIN (-3375 9700) $PN 2
J 0
(-3370 9710);
DISPLAY 0.787234 (-3370 9710);
FORCEPROP 2 LAST CDS_LIB pure_quanta
J 0
(-3375 9800);
PAINT MONO (-3375 9800);
DISPLAY INVISIBLE (-3375 9800);
FORCEPROP 1 LAST PATH I269
J 0
(-3325 9975);
DISPLAY 0.978723 (-3325 9975);
PAINT WHITE (-3325 9975);
DISPLAY INVISIBLE (-3325 9975);
FORCEPROP 2 LAST CDS_LOCATION R1527
J 0
(-3325 10025);
DISPLAY 1.021277 (-3325 10025);
DISPLAY INVISIBLE (-3325 10025);
FORCEPROP 2 LAST $SEC 1
J 0
(-3325 10025);
DISPLAY 0.680851 (-3325 10025);
PAINT MONO (-3325 10025);
DISPLAY INVISIBLE (-3325 10025);
FORCEPROP 2 LAST CDS_SEC 1
J 0
(-3325 10025);
DISPLAY 1.021277 (-3325 10025);
DISPLAY INVISIBLE (-3325 10025);
FORCEADD Q_RES..2
(-3625 9800);
FORCEPROP 1 LAST PART_NUMBER CS24752FB03
J 0
(-3585 9675);
DISPLAY 0.638298 (-3585 9675);
DISPLAY INVISIBLE (-3585 9675);
FORCEPROP 1 LAST TOLERANCE 1%
J 0
(-3580 9825);
DISPLAY 0.638298 (-3580 9825);
FORCEPROP 1 LAST PACK_TYPE 0402LF
J 0
(-3585 9675);
DISPLAY 0.638298 (-3585 9675);
FORCEPROP 1 LAST WATTAGE 1/16W
J 0
(-3585 9775);
DISPLAY 0.638298 (-3585 9775);
FORCEPROP 1 LAST MATERIAL CHIP
J 0
(-3585 9725);
DISPLAY 0.638298 (-3585 9725);
FORCEPROP 1 LAST VALUE 4.75K
J 0
(-3580 9875);
DISPLAY 0.638298 (-3580 9875);
FORCEPROP 1 LAST $LOCATION R1502
J 0
(-3580 9925);
DISPLAY 0.638298 (-3580 9925);
FORCEPROP 1 LASTPIN (-3625 9900) $PN 1
J 0
(-3620 9862);
DISPLAY 0.787234 (-3620 9862);
FORCEPROP 1 LASTPIN (-3625 9700) $PN 2
J 0
(-3620 9710);
DISPLAY 0.787234 (-3620 9710);
FORCEPROP 2 LAST CDS_LIB pure_quanta
J 0
(-3625 9800);
PAINT MONO (-3625 9800);
DISPLAY INVISIBLE (-3625 9800);
FORCEPROP 1 LAST PATH I270
J 0
(-3575 9975);
DISPLAY 0.978723 (-3575 9975);
PAINT WHITE (-3575 9975);
DISPLAY INVISIBLE (-3575 9975);
FORCEPROP 2 LAST CDS_LOCATION R1502
J 0
(-3575 10025);
DISPLAY 1.021277 (-3575 10025);
DISPLAY INVISIBLE (-3575 10025);
FORCEPROP 2 LAST $SEC 1
J 0
(-3575 10025);
DISPLAY 0.680851 (-3575 10025);
PAINT MONO (-3575 10025);
DISPLAY INVISIBLE (-3575 10025);
FORCEPROP 2 LAST CDS_SEC 1
J 0
(-3575 10025);
DISPLAY 1.021277 (-3575 10025);
DISPLAY INVISIBLE (-3575 10025);
FORCEADD Q_RES..2
(-3875 9800);
FORCEPROP 1 LAST PART_NUMBER CS24752FB03
J 0
(-3835 9675);
DISPLAY 0.638298 (-3835 9675);
DISPLAY INVISIBLE (-3835 9675);
FORCEPROP 1 LAST PACK_TYPE 0402LF
J 0
(-3835 9675);
DISPLAY 0.638298 (-3835 9675);
FORCEPROP 1 LAST VALUE 4.75K
J 0
(-3830 9875);
DISPLAY 0.638298 (-3830 9875);
FORCEPROP 1 LAST TOLERANCE 1%
J 0
(-3830 9825);
DISPLAY 0.638298 (-3830 9825);
FORCEPROP 1 LAST WATTAGE 1/16W
J 0
(-3835 9775);
DISPLAY 0.638298 (-3835 9775);
FORCEPROP 1 LAST MATERIAL CHIP
J 0
(-3835 9725);
DISPLAY 0.638298 (-3835 9725);
FORCEPROP 1 LAST $LOCATION R1500
J 0
(-3830 9925);
DISPLAY 0.638298 (-3830 9925);
FORCEPROP 1 LASTPIN (-3875 9900) $PN 1
J 0
(-3870 9862);
DISPLAY 0.787234 (-3870 9862);
FORCEPROP 1 LASTPIN (-3875 9700) $PN 2
J 0
(-3870 9710);
DISPLAY 0.787234 (-3870 9710);
FORCEPROP 2 LAST CDS_LIB pure_quanta
J 0
(-3875 9800);
PAINT MONO (-3875 9800);
DISPLAY INVISIBLE (-3875 9800);
FORCEPROP 1 LAST PATH I271
J 0
(-3825 9975);
DISPLAY 0.978723 (-3825 9975);
PAINT WHITE (-3825 9975);
DISPLAY INVISIBLE (-3825 9975);
FORCEPROP 2 LAST CDS_LOCATION R1500
J 0
(-3825 10025);
DISPLAY 1.021277 (-3825 10025);
DISPLAY INVISIBLE (-3825 10025);
FORCEPROP 2 LAST $SEC 1
J 0
(-3825 10025);
DISPLAY 0.680851 (-3825 10025);
PAINT MONO (-3825 10025);
DISPLAY INVISIBLE (-3825 10025);
FORCEPROP 2 LAST CDS_SEC 1
J 0
(-3825 10025);
DISPLAY 1.021277 (-3825 10025);
DISPLAY INVISIBLE (-3825 10025);
FORCEADD Q_RES..2
(-4400 10725);
FORCEPROP 1 LAST PART_NUMBER CS31002FB08
J 0
(-4360 10600);
DISPLAY 0.638298 (-4360 10600);
DISPLAY INVISIBLE (-4360 10600);
FORCEPROP 1 LAST MATERIAL EMPTY
J 0
(-4360 10650);
DISPLAY 0.638298 (-4360 10650);
PAINT RED (-4360 10650);
FORCEPROP 1 LAST WATTAGE 1/16W
J 0
(-4360 10700);
DISPLAY 0.638298 (-4360 10700);
FORCEPROP 1 LAST PACK_TYPE 0402LF
J 0
(-4360 10600);
DISPLAY 0.638298 (-4360 10600);
FORCEPROP 1 LAST TOLERANCE 1%
J 0
(-4355 10750);
DISPLAY 0.638298 (-4355 10750);
FORCEPROP 1 LAST VALUE 10K
J 0
(-4355 10800);
DISPLAY 0.638298 (-4355 10800);
FORCEPROP 1 LAST $LOCATION R1305
J 0
(-4355 10850);
DISPLAY 0.638298 (-4355 10850);
FORCEPROP 1 LASTPIN (-4400 10825) $PN 1
J 0
(-4395 10787);
DISPLAY 0.787234 (-4395 10787);
FORCEPROP 1 LASTPIN (-4400 10625) $PN 2
J 0
(-4395 10635);
DISPLAY 0.787234 (-4395 10635);
FORCEPROP 2 LAST CDS_LIB pure_quanta
J 0
(-4400 10725);
PAINT MONO (-4400 10725);
DISPLAY INVISIBLE (-4400 10725);
FORCEPROP 1 LAST PATH I272
J 0
(-4350 10900);
DISPLAY 0.978723 (-4350 10900);
PAINT WHITE (-4350 10900);
DISPLAY INVISIBLE (-4350 10900);
FORCEPROP 2 LAST CDS_LOCATION R1305
J 0
(-4350 10950);
DISPLAY 1.021277 (-4350 10950);
DISPLAY INVISIBLE (-4350 10950);
FORCEPROP 2 LAST $SEC 1
J 0
(-4350 10950);
DISPLAY 0.680851 (-4350 10950);
PAINT MONO (-4350 10950);
DISPLAY INVISIBLE (-4350 10950);
FORCEPROP 2 LAST CDS_SEC 1
J 0
(-4350 10950);
DISPLAY 1.021277 (-4350 10950);
DISPLAY INVISIBLE (-4350 10950);
FORCEADD Q_RES..2
(-4675 10725);
FORCEPROP 1 LAST PART_NUMBER CS31002FB08
J 0
(-4635 10600);
DISPLAY 0.638298 (-4635 10600);
DISPLAY INVISIBLE (-4635 10600);
FORCEPROP 1 LAST WATTAGE 1/16W
J 0
(-4635 10700);
DISPLAY 0.638298 (-4635 10700);
FORCEPROP 1 LAST MATERIAL EMPTY
J 0
(-4635 10650);
DISPLAY 0.638298 (-4635 10650);
PAINT RED (-4635 10650);
FORCEPROP 1 LAST TOLERANCE 1%
J 0
(-4630 10750);
DISPLAY 0.638298 (-4630 10750);
FORCEPROP 1 LAST PACK_TYPE 0402LF
J 0
(-4635 10600);
DISPLAY 0.638298 (-4635 10600);
FORCEPROP 1 LAST VALUE 10K
J 0
(-4630 10800);
DISPLAY 0.638298 (-4630 10800);
FORCEPROP 1 LAST $LOCATION R1204
J 0
(-4630 10850);
DISPLAY 0.638298 (-4630 10850);
FORCEPROP 1 LASTPIN (-4675 10825) $PN 1
J 0
(-4670 10787);
DISPLAY 0.787234 (-4670 10787);
FORCEPROP 1 LASTPIN (-4675 10625) $PN 2
J 0
(-4670 10635);
DISPLAY 0.787234 (-4670 10635);
FORCEPROP 1 LAST PATH I273
J 0
(-4625 10900);
DISPLAY 0.978723 (-4625 10900);
PAINT WHITE (-4625 10900);
DISPLAY INVISIBLE (-4625 10900);
FORCEPROP 2 LAST CDS_LIB pure_quanta
J 0
(-4675 10725);
PAINT MONO (-4675 10725);
DISPLAY INVISIBLE (-4675 10725);
FORCEPROP 2 LAST CDS_LOCATION R1204
J 0
(-4625 10950);
DISPLAY 1.021277 (-4625 10950);
DISPLAY INVISIBLE (-4625 10950);
FORCEPROP 2 LAST $SEC 1
J 0
(-4625 10950);
DISPLAY 0.680851 (-4625 10950);
PAINT MONO (-4625 10950);
DISPLAY INVISIBLE (-4625 10950);
FORCEPROP 2 LAST CDS_SEC 1
J 0
(-4625 10950);
DISPLAY 1.021277 (-4625 10950);
DISPLAY INVISIBLE (-4625 10950);
FORCEADD Q_RES..2
(-4125 9800);
FORCEPROP 1 LAST PART_NUMBER CS21002FB06
J 0
(-4085 9675);
DISPLAY 0.638298 (-4085 9675);
DISPLAY INVISIBLE (-4085 9675);
FORCEPROP 1 LAST VALUE 1K
J 0
(-4080 9875);
DISPLAY 0.638298 (-4080 9875);
FORCEPROP 1 LAST TOLERANCE 1%
J 0
(-4080 9825);
DISPLAY 0.638298 (-4080 9825);
FORCEPROP 1 LAST MATERIAL CHIP
J 0
(-4085 9725);
DISPLAY 0.638298 (-4085 9725);
FORCEPROP 1 LAST WATTAGE 1/16W
J 0
(-4085 9775);
DISPLAY 0.638298 (-4085 9775);
FORCEPROP 1 LAST PACK_TYPE 0402LF
J 0
(-4085 9675);
DISPLAY 0.638298 (-4085 9675);
FORCEPROP 1 LAST $LOCATION R1462
J 0
(-4080 9925);
DISPLAY 0.638298 (-4080 9925);
FORCEPROP 1 LASTPIN (-4125 9900) $PN 1
J 0
(-4120 9862);
DISPLAY 0.787234 (-4120 9862);
FORCEPROP 1 LASTPIN (-4125 9700) $PN 2
J 0
(-4120 9710);
DISPLAY 0.787234 (-4120 9710);
FORCEPROP 2 LAST CDS_LIB pure_quanta
J 0
(-4125 9800);
PAINT MONO (-4125 9800);
DISPLAY INVISIBLE (-4125 9800);
FORCEPROP 1 LAST PATH I274
J 0
(-4075 9975);
DISPLAY 0.978723 (-4075 9975);
PAINT WHITE (-4075 9975);
DISPLAY INVISIBLE (-4075 9975);
FORCEPROP 2 LAST CDS_LOCATION R1462
J 0
(-4075 10025);
DISPLAY 1.021277 (-4075 10025);
DISPLAY INVISIBLE (-4075 10025);
FORCEPROP 2 LAST $SEC 1
J 0
(-4075 10025);
DISPLAY 0.680851 (-4075 10025);
PAINT MONO (-4075 10025);
DISPLAY INVISIBLE (-4075 10025);
FORCEPROP 2 LAST CDS_SEC 1
J 0
(-4075 10025);
DISPLAY 1.021277 (-4075 10025);
DISPLAY INVISIBLE (-4075 10025);
FORCEADD Q_RES..2
(-4400 9800);
FORCEPROP 1 LAST PART_NUMBER CS21002FB06
J 0
(-4360 9675);
DISPLAY 0.638298 (-4360 9675);
DISPLAY INVISIBLE (-4360 9675);
FORCEPROP 1 LAST VALUE 1K
J 0
(-4355 9875);
DISPLAY 0.638298 (-4355 9875);
FORCEPROP 1 LAST TOLERANCE 1%
J 0
(-4355 9825);
DISPLAY 0.638298 (-4355 9825);
FORCEPROP 1 LAST MATERIAL EMPTY
J 0
(-4360 9725);
DISPLAY 0.638298 (-4360 9725);
PAINT RED (-4360 9725);
FORCEPROP 1 LAST WATTAGE 1/16W
J 0
(-4360 9775);
DISPLAY 0.638298 (-4360 9775);
FORCEPROP 1 LAST PACK_TYPE 0402LF
J 0
(-4360 9675);
DISPLAY 0.638298 (-4360 9675);
FORCEPROP 1 LAST $LOCATION R1390
J 0
(-4355 9925);
DISPLAY 0.638298 (-4355 9925);
FORCEPROP 1 LASTPIN (-4400 9900) $PN 1
J 0
(-4395 9862);
DISPLAY 0.787234 (-4395 9862);
FORCEPROP 1 LASTPIN (-4400 9700) $PN 2
J 0
(-4395 9710);
DISPLAY 0.787234 (-4395 9710);
FORCEPROP 2 LAST CDS_LIB pure_quanta
J 0
(-4400 9800);
PAINT MONO (-4400 9800);
DISPLAY INVISIBLE (-4400 9800);
FORCEPROP 1 LAST PATH I275
J 0
(-4350 9975);
DISPLAY 0.978723 (-4350 9975);
PAINT WHITE (-4350 9975);
DISPLAY INVISIBLE (-4350 9975);
FORCEPROP 2 LAST CDS_LOCATION R1390
J 0
(-4350 10025);
DISPLAY 1.021277 (-4350 10025);
DISPLAY INVISIBLE (-4350 10025);
FORCEPROP 2 LAST $SEC 1
J 0
(-4350 10025);
DISPLAY 0.680851 (-4350 10025);
PAINT MONO (-4350 10025);
DISPLAY INVISIBLE (-4350 10025);
FORCEPROP 2 LAST CDS_SEC 1
J 0
(-4350 10025);
DISPLAY 1.021277 (-4350 10025);
DISPLAY INVISIBLE (-4350 10025);
FORCEADD Q_RES..2
(-4675 9800);
FORCEPROP 1 LAST PART_NUMBER CS21002FB06
J 0
(-4635 9675);
DISPLAY 0.638298 (-4635 9675);
DISPLAY INVISIBLE (-4635 9675);
FORCEPROP 1 LAST TOLERANCE 1%
J 0
(-4630 9825);
DISPLAY 0.638298 (-4630 9825);
FORCEPROP 1 LAST VALUE 1K
J 0
(-4630 9875);
DISPLAY 0.638298 (-4630 9875);
FORCEPROP 1 LAST WATTAGE 1/16W
J 0
(-4635 9775);
DISPLAY 0.638298 (-4635 9775);
FORCEPROP 1 LAST MATERIAL CHIP
J 0
(-4635 9725);
DISPLAY 0.638298 (-4635 9725);
FORCEPROP 1 LAST PACK_TYPE 0402LF
J 0
(-4635 9675);
DISPLAY 0.638298 (-4635 9675);
FORCEPROP 1 LAST $LOCATION R1267
J 0
(-4630 9925);
DISPLAY 0.638298 (-4630 9925);
FORCEPROP 1 LASTPIN (-4675 9900) $PN 1
J 0
(-4670 9862);
DISPLAY 0.787234 (-4670 9862);
FORCEPROP 1 LASTPIN (-4675 9700) $PN 2
J 0
(-4670 9710);
DISPLAY 0.787234 (-4670 9710);
FORCEPROP 1 LAST PATH I276
J 0
(-4625 9975);
DISPLAY 0.978723 (-4625 9975);
PAINT WHITE (-4625 9975);
DISPLAY INVISIBLE (-4625 9975);
FORCEPROP 2 LAST CDS_LIB pure_quanta
J 0
(-4675 9800);
PAINT MONO (-4675 9800);
DISPLAY INVISIBLE (-4675 9800);
FORCEPROP 2 LAST CDS_LOCATION R1267
J 0
(-4625 10025);
DISPLAY 1.021277 (-4625 10025);
DISPLAY INVISIBLE (-4625 10025);
FORCEPROP 2 LAST $SEC 1
J 0
(-4625 10025);
DISPLAY 0.680851 (-4625 10025);
PAINT MONO (-4625 10025);
DISPLAY INVISIBLE (-4625 10025);
FORCEPROP 2 LAST CDS_SEC 1
J 0
(-4625 10025);
DISPLAY 1.021277 (-4625 10025);
DISPLAY INVISIBLE (-4625 10025);
FORCEADD Q_RES..2
(-5100 10725);
FORCEPROP 1 LAST PART_NUMBER CS24752FB03
J 0
(-5060 10600);
DISPLAY 0.638298 (-5060 10600);
DISPLAY INVISIBLE (-5060 10600);
FORCEPROP 1 LAST TOLERANCE 1%
J 0
(-5055 10750);
DISPLAY 0.638298 (-5055 10750);
FORCEPROP 1 LAST WATTAGE 1/16W
J 0
(-5060 10700);
DISPLAY 0.638298 (-5060 10700);
FORCEPROP 1 LAST VALUE 4.75K
J 0
(-5055 10800);
DISPLAY 0.638298 (-5055 10800);
FORCEPROP 1 LAST MATERIAL EMPTY
J 0
(-5060 10650);
DISPLAY 0.638298 (-5060 10650);
PAINT RED (-5060 10650);
FORCEPROP 1 LAST PACK_TYPE 0402LF
J 0
(-5060 10550);
DISPLAY 0.638298 (-5060 10550);
FORCEPROP 1 LAST $LOCATION R1194
J 0
(-5055 10850);
DISPLAY 0.638298 (-5055 10850);
FORCEPROP 1 LASTPIN (-5100 10825) $PN 1
J 0
(-5095 10787);
DISPLAY 0.787234 (-5095 10787);
FORCEPROP 1 LASTPIN (-5100 10625) $PN 2
J 0
(-5095 10635);
DISPLAY 0.787234 (-5095 10635);
FORCEPROP 2 LAST CDS_LIB pure_quanta
J 0
(-5100 10725);
PAINT MONO (-5100 10725);
DISPLAY INVISIBLE (-5100 10725);
FORCEPROP 1 LAST PATH I277
J 0
(-5050 10900);
DISPLAY 0.978723 (-5050 10900);
PAINT WHITE (-5050 10900);
DISPLAY INVISIBLE (-5050 10900);
FORCEPROP 2 LAST CDS_LOCATION R1194
J 0
(-5050 10950);
DISPLAY 1.021277 (-5050 10950);
DISPLAY INVISIBLE (-5050 10950);
FORCEPROP 2 LAST $SEC 1
J 0
(-5050 10950);
DISPLAY 0.680851 (-5050 10950);
PAINT MONO (-5050 10950);
DISPLAY INVISIBLE (-5050 10950);
FORCEPROP 2 LAST CDS_SEC 1
J 0
(-5050 10950);
DISPLAY 1.021277 (-5050 10950);
DISPLAY INVISIBLE (-5050 10950);
FORCEADD Q_RES..2
(-5350 10725);
FORCEPROP 1 LAST PART_NUMBER CS24752FB03
J 0
(-5310 10600);
DISPLAY 0.638298 (-5310 10600);
DISPLAY INVISIBLE (-5310 10600);
FORCEPROP 1 LAST TOLERANCE 1%
J 0
(-5305 10750);
DISPLAY 0.638298 (-5305 10750);
FORCEPROP 1 LAST MATERIAL EMPTY
J 0
(-5310 10650);
DISPLAY 0.638298 (-5310 10650);
PAINT RED (-5310 10650);
FORCEPROP 1 LAST PACK_TYPE 0402LF
J 0
(-5310 10600);
DISPLAY 0.638298 (-5310 10600);
FORCEPROP 1 LAST VALUE 4.75K
J 0
(-5305 10800);
DISPLAY 0.638298 (-5305 10800);
FORCEPROP 1 LAST WATTAGE 1/16W
J 0
(-5310 10700);
DISPLAY 0.638298 (-5310 10700);
FORCEPROP 1 LAST $LOCATION R912
J 0
(-5305 10850);
DISPLAY 0.638298 (-5305 10850);
FORCEPROP 1 LASTPIN (-5350 10825) $PN 1
J 0
(-5345 10787);
DISPLAY 0.787234 (-5345 10787);
FORCEPROP 1 LASTPIN (-5350 10625) $PN 2
J 0
(-5345 10635);
DISPLAY 0.787234 (-5345 10635);
FORCEPROP 2 LAST CDS_LIB pure_quanta
J 0
(-5350 10725);
PAINT MONO (-5350 10725);
DISPLAY INVISIBLE (-5350 10725);
FORCEPROP 1 LAST PATH I278
J 0
(-5300 10900);
DISPLAY 0.978723 (-5300 10900);
PAINT WHITE (-5300 10900);
DISPLAY INVISIBLE (-5300 10900);
FORCEPROP 2 LAST CDS_LOCATION R912
J 0
(-5300 10950);
DISPLAY 1.021277 (-5300 10950);
DISPLAY INVISIBLE (-5300 10950);
FORCEPROP 2 LAST $SEC 1
J 0
(-5300 10950);
DISPLAY 0.680851 (-5300 10950);
PAINT MONO (-5300 10950);
DISPLAY INVISIBLE (-5300 10950);
FORCEPROP 2 LAST CDS_SEC 1
J 0
(-5300 10950);
DISPLAY 1.021277 (-5300 10950);
DISPLAY INVISIBLE (-5300 10950);
FORCEADD UNIVERSAL_POWER..1
(-5625 11125);
FORCEPROP 3 LASTPIN (-5625 11075) SIG_NAME P3V3_AUX\g
J 0
(-5615 11085);
DISPLAY 0.659574 (-5615 11085);
PAINT MONO (-5615 11085);
DISPLAY INVISIBLE (-5615 11085);
FORCEPROP 1 LAST HDL_POWER P3V3_AUX
J 1
(-5625 11175);
DISPLAY 0.872340 (-5625 11175);
PAINT GREEN (-5625 11175);
FORCEPROP 1 LAST PATH I279
J 0
(-5575 11150);
DISPLAY 0.872340 (-5575 11150);
PAINT AQUA (-5575 11150);
DISPLAY INVISIBLE (-5575 11150);
FORCEPROP 2 LAST CDS_LIB logical_power
J 0
(-5625 11125);
PAINT MONO (-5625 11125);
DISPLAY INVISIBLE (-5625 11125);
FORCEADD Q_RES..2
(-5625 10725);
FORCEPROP 1 LAST PART_NUMBER CS24752FB03
J 0
(-5585 10600);
DISPLAY 0.638298 (-5585 10600);
DISPLAY INVISIBLE (-5585 10600);
FORCEPROP 1 LAST TOLERANCE 1%
J 0
(-5580 10750);
DISPLAY 0.638298 (-5580 10750);
FORCEPROP 1 LAST PACK_TYPE 0402LF
J 0
(-5585 10600);
DISPLAY 0.638298 (-5585 10600);
FORCEPROP 1 LAST VALUE 4.75K
J 0
(-5580 10800);
DISPLAY 0.638298 (-5580 10800);
FORCEPROP 1 LAST MATERIAL EMPTY
J 0
(-5585 10650);
DISPLAY 0.638298 (-5585 10650);
PAINT RED (-5585 10650);
FORCEPROP 1 LAST WATTAGE 1/16W
J 0
(-5585 10700);
DISPLAY 0.638298 (-5585 10700);
FORCEPROP 1 LAST $LOCATION R2481
J 0
(-5580 10850);
DISPLAY 0.638298 (-5580 10850);
FORCEPROP 1 LASTPIN (-5625 10825) $PN 1
J 0
(-5620 10787);
DISPLAY 0.787234 (-5620 10787);
FORCEPROP 1 LASTPIN (-5625 10625) $PN 2
J 0
(-5620 10635);
DISPLAY 0.787234 (-5620 10635);
FORCEPROP 2 LAST CDS_LIB pure_quanta
J 0
(-5625 10725);
PAINT MONO (-5625 10725);
DISPLAY INVISIBLE (-5625 10725);
FORCEPROP 1 LAST PATH I280
J 0
(-5575 10900);
DISPLAY 0.978723 (-5575 10900);
PAINT WHITE (-5575 10900);
DISPLAY INVISIBLE (-5575 10900);
FORCEPROP 2 LAST CDS_LOCATION R2481
J 0
(-5575 10950);
DISPLAY 1.021277 (-5575 10950);
DISPLAY INVISIBLE (-5575 10950);
FORCEPROP 2 LAST $SEC 1
J 0
(-5575 10950);
DISPLAY 0.680851 (-5575 10950);
PAINT MONO (-5575 10950);
DISPLAY INVISIBLE (-5575 10950);
FORCEPROP 2 LAST CDS_SEC 1
J 0
(-5575 10950);
DISPLAY 1.021277 (-5575 10950);
DISPLAY INVISIBLE (-5575 10950);
FORCEADD Q_RES..2
(-5100 9800);
FORCEPROP 1 LAST PART_NUMBER CS24752FB03
J 0
(-5060 9675);
DISPLAY 0.638298 (-5060 9675);
DISPLAY INVISIBLE (-5060 9675);
FORCEPROP 1 LAST PACK_TYPE 0402LF
J 0
(-5060 9625);
DISPLAY 0.638298 (-5060 9625);
FORCEPROP 1 LAST VALUE 4.75K
J 0
(-5055 9875);
DISPLAY 0.638298 (-5055 9875);
FORCEPROP 1 LAST WATTAGE 1/16W
J 0
(-5060 9775);
DISPLAY 0.638298 (-5060 9775);
FORCEPROP 1 LAST TOLERANCE 1%
J 0
(-5055 9825);
DISPLAY 0.638298 (-5055 9825);
FORCEPROP 1 LAST MATERIAL CHIP
J 0
(-5060 9725);
DISPLAY 0.638298 (-5060 9725);
FORCEPROP 1 LAST $LOCATION R1196
J 0
(-5055 9925);
DISPLAY 0.638298 (-5055 9925);
FORCEPROP 1 LASTPIN (-5100 9900) $PN 1
J 0
(-5095 9862);
DISPLAY 0.787234 (-5095 9862);
FORCEPROP 1 LASTPIN (-5100 9700) $PN 2
J 0
(-5095 9710);
DISPLAY 0.787234 (-5095 9710);
FORCEPROP 2 LAST CDS_LIB pure_quanta
J 0
(-5100 9800);
PAINT MONO (-5100 9800);
DISPLAY INVISIBLE (-5100 9800);
FORCEPROP 1 LAST PATH I281
J 0
(-5050 9975);
DISPLAY 0.978723 (-5050 9975);
PAINT WHITE (-5050 9975);
DISPLAY INVISIBLE (-5050 9975);
FORCEPROP 2 LAST CDS_LOCATION R1196
J 0
(-5050 10025);
DISPLAY 1.021277 (-5050 10025);
DISPLAY INVISIBLE (-5050 10025);
FORCEPROP 2 LAST $SEC 1
J 0
(-5050 10025);
DISPLAY 0.680851 (-5050 10025);
PAINT MONO (-5050 10025);
DISPLAY INVISIBLE (-5050 10025);
FORCEPROP 2 LAST CDS_SEC 1
J 0
(-5050 10025);
DISPLAY 1.021277 (-5050 10025);
DISPLAY INVISIBLE (-5050 10025);
FORCEADD Q_RES..2
(-5350 9800);
FORCEPROP 1 LAST PART_NUMBER CS24752FB03
J 0
(-5310 9675);
DISPLAY 0.638298 (-5310 9675);
DISPLAY INVISIBLE (-5310 9675);
FORCEPROP 1 LAST VALUE 4.75K
J 0
(-5305 9875);
DISPLAY 0.638298 (-5305 9875);
FORCEPROP 1 LAST MATERIAL CHIP
J 0
(-5310 9725);
DISPLAY 0.638298 (-5310 9725);
FORCEPROP 1 LAST TOLERANCE 1%
J 0
(-5305 9825);
DISPLAY 0.638298 (-5305 9825);
FORCEPROP 1 LAST PACK_TYPE 0402LF
J 0
(-5310 9675);
DISPLAY 0.638298 (-5310 9675);
FORCEPROP 1 LAST WATTAGE 1/16W
J 0
(-5310 9775);
DISPLAY 0.638298 (-5310 9775);
FORCEPROP 1 LAST $LOCATION R953
J 0
(-5305 9925);
DISPLAY 0.638298 (-5305 9925);
FORCEPROP 1 LASTPIN (-5350 9900) $PN 1
J 0
(-5345 9862);
DISPLAY 0.787234 (-5345 9862);
FORCEPROP 1 LASTPIN (-5350 9700) $PN 2
J 0
(-5345 9710);
DISPLAY 0.787234 (-5345 9710);
FORCEPROP 2 LAST CDS_LIB pure_quanta
J 0
(-5350 9800);
PAINT MONO (-5350 9800);
DISPLAY INVISIBLE (-5350 9800);
FORCEPROP 1 LAST PATH I282
J 0
(-5300 9975);
DISPLAY 0.978723 (-5300 9975);
PAINT WHITE (-5300 9975);
DISPLAY INVISIBLE (-5300 9975);
FORCEPROP 2 LAST CDS_LOCATION R953
J 0
(-5300 10025);
DISPLAY 1.021277 (-5300 10025);
DISPLAY INVISIBLE (-5300 10025);
FORCEPROP 2 LAST $SEC 1
J 0
(-5300 10025);
DISPLAY 0.680851 (-5300 10025);
PAINT MONO (-5300 10025);
DISPLAY INVISIBLE (-5300 10025);
FORCEPROP 2 LAST CDS_SEC 1
J 0
(-5300 10025);
DISPLAY 1.021277 (-5300 10025);
DISPLAY INVISIBLE (-5300 10025);
FORCEADD Q_RES..2
(-5625 9800);
FORCEPROP 1 LAST PART_NUMBER CS24752FB03
J 0
(-5585 9675);
DISPLAY 0.638298 (-5585 9675);
DISPLAY INVISIBLE (-5585 9675);
FORCEPROP 1 LAST PACK_TYPE 0402LF
J 0
(-5585 9675);
DISPLAY 0.638298 (-5585 9675);
FORCEPROP 1 LAST MATERIAL CHIP
J 0
(-5585 9725);
DISPLAY 0.638298 (-5585 9725);
FORCEPROP 1 LAST TOLERANCE 1%
J 0
(-5580 9825);
DISPLAY 0.638298 (-5580 9825);
FORCEPROP 1 LAST WATTAGE 1/16W
J 0
(-5585 9775);
DISPLAY 0.638298 (-5585 9775);
FORCEPROP 1 LAST VALUE 4.75K
J 0
(-5580 9875);
DISPLAY 0.638298 (-5580 9875);
FORCEPROP 1 LAST $LOCATION R734
J 0
(-5580 9925);
DISPLAY 0.638298 (-5580 9925);
FORCEPROP 1 LASTPIN (-5625 9900) $PN 1
J 0
(-5620 9862);
DISPLAY 0.787234 (-5620 9862);
FORCEPROP 1 LASTPIN (-5625 9700) $PN 2
J 0
(-5620 9710);
DISPLAY 0.787234 (-5620 9710);
FORCEPROP 2 LAST CDS_LIB pure_quanta
J 0
(-5625 9800);
PAINT MONO (-5625 9800);
DISPLAY INVISIBLE (-5625 9800);
FORCEPROP 1 LAST PATH I283
J 0
(-5575 9975);
DISPLAY 0.978723 (-5575 9975);
PAINT WHITE (-5575 9975);
DISPLAY INVISIBLE (-5575 9975);
FORCEPROP 2 LAST CDS_LOCATION R734
J 0
(-5575 10025);
DISPLAY 1.021277 (-5575 10025);
DISPLAY INVISIBLE (-5575 10025);
FORCEPROP 2 LAST $SEC 1
J 0
(-5575 10025);
DISPLAY 0.680851 (-5575 10025);
PAINT MONO (-5575 10025);
DISPLAY INVISIBLE (-5575 10025);
FORCEPROP 2 LAST CDS_SEC 1
J 0
(-5575 10025);
DISPLAY 1.021277 (-5575 10025);
DISPLAY INVISIBLE (-5575 10025);
FORCEADD UNIVERSAL_GND..1
(-1950 5550);
FORCEPROP 3 LASTPIN (-1950 5600) SIG_NAME GND\g
J 0
(-1940 5610);
DISPLAY 0.659574 (-1940 5610);
PAINT MONO (-1940 5610);
DISPLAY INVISIBLE (-1940 5610);
FORCEPROP 2 LAST CDS_LIB logical_power
J 0
(-1950 5550);
PAINT MONO (-1950 5550);
DISPLAY INVISIBLE (-1950 5550);
FORCEPROP 1 LAST PATH I285
J 0
(-1875 5550);
DISPLAY 0.872340 (-1875 5550);
PAINT AQUA (-1875 5550);
DISPLAY INVISIBLE (-1875 5550);
FORCEPROP 1 LAST HDL_POWER GND
J 1
(-1925 5475);
DISPLAY 0.872340 (-1925 5475);
PAINT GREEN (-1925 5475);
DISPLAY INVISIBLE (-1925 5475);
FORCEADD Q_CAP..1
R 2
(-1950 5775);
FORCEPROP 1 LAST PART_NUMBER CH4104K1B00
J 2
(-2000 5625);
DISPLAY 0.510638 (-2000 5625);
DISPLAY INVISIBLE (-2000 5625);
FORCEPROP 1 LAST PACK_TYPE 0402
J 2
(-2000 5575);
DISPLAY 0.510638 (-2000 5575);
FORCEPROP 1 LAST TOLERANCE 10%
J 2
(-2000 5725);
DISPLAY 0.510638 (-2000 5725);
FORCEPROP 1 LAST VOLTAGE 25V
J 2
(-2000 5775);
DISPLAY 0.510638 (-2000 5775);
FORCEPROP 1 LAST VALUE 0.1UF
J 2
(-2000 5825);
DISPLAY 0.510638 (-2000 5825);
FORCEPROP 1 LAST MATERIAL EMPTY
J 2
(-2000 5675);
DISPLAY 0.510638 (-2000 5675);
FORCEPROP 1 LAST $LOCATION C1324
J 2
(-2000 5875);
DISPLAY 0.787234 (-2000 5875);
FORCEPROP 1 LASTPIN (-1950 5875) $PN 1
J 2
(-1960 5855);
DISPLAY 0.787234 (-1960 5855);
FORCEPROP 1 LASTPIN (-1950 5675) $PN 2
J 2
(-1960 5655);
DISPLAY 0.787234 (-1960 5655);
FORCEPROP 1 LAST PATH I286
J 2
(-2000 5925);
DISPLAY 0.978723 (-2000 5925);
PAINT WHITE (-2000 5925);
DISPLAY INVISIBLE (-2000 5925);
FORCEPROP 2 LAST CDS_LIB pure_quanta
J 0
(-1950 5775);
PAINT MONO (-1950 5775);
DISPLAY INVISIBLE (-1950 5775);
FORCEPROP 2 LAST CDS_LOCATION C1324
J 0
(-2000 5975);
DISPLAY 1.021277 (-2000 5975);
DISPLAY INVISIBLE (-2000 5975);
FORCEPROP 2 LAST $SEC 1
J 0
(-2000 5975);
DISPLAY 0.680851 (-2000 5975);
PAINT MONO (-2000 5975);
DISPLAY INVISIBLE (-2000 5975);
FORCEPROP 2 LAST CDS_SEC 1
J 0
(-2000 5975);
DISPLAY 1.021277 (-2000 5975);
DISPLAY INVISIBLE (-2000 5975);
FORCEADD 9SQ440NQQI8..2
(-25 10275);
FORCEPROP 1 LAST PART_NUMBER AJ004400000
J 0
(-375 10775);
DISPLAY 0.723404 (-375 10775);
PAINT GREEN (-375 10775);
DISPLAY INVISIBLE (-375 10775);
FORCEPROP 1 LAST MATERIAL IC
J 0
(-375 10700);
DISPLAY 0.723404 (-375 10700);
PAINT GREEN (-375 10700);
FORCEPROP 2 LAST VALUE 9SQ440NQQI8
J 0
(-375 10925);
DISPLAY 1.021277 (-375 10925);
FORCEPROP 2 LAST PART_TYPE SMLF
J 0
(-375 10975);
DISPLAY 1.021277 (-375 10975);
FORCEPROP 1 LAST $LOCATION U13
J 0
(-375 10850);
DISPLAY 0.723404 (-375 10850);
PAINT GREEN (-375 10850);
FORCEPROP 0 LASTPIN (475 10525) $PN A15
J 0
(485 10535);
DISPLAY 0.680851 (485 10535);
PAINT MONO (485 10535);
FORCEPROP 0 LASTPIN (475 10475) $PN B2
J 0
(485 10485);
DISPLAY 0.680851 (485 10485);
PAINT MONO (485 10485);
FORCEPROP 0 LASTPIN (475 10425) $PN B3
J 0
(485 10435);
DISPLAY 0.680851 (485 10435);
PAINT MONO (485 10435);
FORCEPROP 0 LASTPIN (475 10375) $PN B5
J 0
(485 10385);
DISPLAY 0.680851 (485 10385);
PAINT MONO (485 10385);
FORCEPROP 0 LASTPIN (475 10325) $PN B7
J 0
(485 10335);
DISPLAY 0.680851 (485 10335);
PAINT MONO (485 10335);
FORCEPROP 0 LASTPIN (475 10275) $PN B13
J 0
(485 10285);
DISPLAY 0.680851 (485 10285);
PAINT MONO (485 10285);
FORCEPROP 0 LASTPIN (475 10225) $PN B16
J 0
(485 10235);
DISPLAY 0.680851 (485 10235);
PAINT MONO (485 10235);
FORCEPROP 0 LASTPIN (475 10175) $PN B18
J 0
(485 10185);
DISPLAY 0.680851 (485 10185);
PAINT MONO (485 10185);
FORCEPROP 0 LASTPIN (475 10125) $PN B20
J 0
(485 10135);
DISPLAY 0.680851 (485 10135);
PAINT MONO (485 10135);
FORCEPROP 0 LASTPIN (475 10075) $PN B22
J 0
(485 10085);
DISPLAY 0.680851 (485 10085);
PAINT MONO (485 10085);
FORCEPROP 0 LASTPIN (475 10575) $PN B24
J 0
(485 10585);
DISPLAY 0.680851 (485 10585);
PAINT MONO (485 10585);
FORCEPROP 0 LASTPIN (-525 10025) $PN B25
J 2
(-535 10035);
DISPLAY 0.680851 (-535 10035);
PAINT MONO (-535 10035);
FORCEPROP 0 LASTPIN (-525 10075) $PN B26
J 2
(-535 10085);
DISPLAY 0.680851 (-535 10085);
PAINT MONO (-535 10085);
FORCEPROP 0 LASTPIN (-525 10125) $PN B28
J 2
(-535 10135);
DISPLAY 0.680851 (-535 10135);
PAINT MONO (-535 10135);
FORCEPROP 0 LASTPIN (-525 10175) $PN B30
J 2
(-535 10185);
DISPLAY 0.680851 (-535 10185);
PAINT MONO (-535 10185);
FORCEPROP 0 LASTPIN (-525 10225) $PN B31
J 2
(-535 10235);
DISPLAY 0.680851 (-535 10235);
PAINT MONO (-535 10235);
FORCEPROP 0 LASTPIN (-525 10275) $PN B33
J 2
(-535 10285);
DISPLAY 0.680851 (-535 10285);
PAINT MONO (-535 10285);
FORCEPROP 0 LASTPIN (-525 10325) $PN B34
J 2
(-535 10335);
DISPLAY 0.680851 (-535 10335);
PAINT MONO (-535 10335);
FORCEPROP 0 LASTPIN (-525 10375) $PN B36
J 2
(-535 10385);
DISPLAY 0.680851 (-535 10385);
PAINT MONO (-535 10385);
FORCEPROP 0 LASTPIN (-525 10425) $PN B37
J 2
(-535 10435);
DISPLAY 0.680851 (-535 10435);
PAINT MONO (-535 10435);
FORCEPROP 0 LASTPIN (-525 10475) $PN B39
J 2
(-535 10485);
DISPLAY 0.680851 (-535 10485);
PAINT MONO (-535 10485);
FORCEPROP 0 LASTPIN (-525 10525) $PN B41
J 2
(-535 10535);
DISPLAY 0.680851 (-535 10535);
PAINT MONO (-535 10535);
FORCEPROP 0 LASTPIN (-525 10575) $PN B44
J 2
(-535 10585);
DISPLAY 0.680851 (-535 10585);
PAINT MONO (-535 10585);
FORCEPROP 2 LAST CDS_LIB pure_quanta
J 0
(-25 10275);
PAINT MONO (-25 10275);
DISPLAY INVISIBLE (-25 10275);
FORCEPROP 1 LAST NEEDS_NO_SIZE TRUE
J 0
(-25 10275);
DISPLAY 0.723404 (-25 10275);
PAINT GREEN (-25 10275);
DISPLAY INVISIBLE (-25 10275);
FORCEPROP 1 LAST PATH I288
J 0
(-25 10275);
DISPLAY 0.723404 (-25 10275);
PAINT GREEN (-25 10275);
DISPLAY INVISIBLE (-25 10275);
FORCEPROP 1 LAST CDS_LMAN_SYM_OUTLINE -350,400,350,-350
J 0
(-25 10275);
DISPLAY 0.468085 (-25 10275);
PAINT GREEN (-25 10275);
DISPLAY INVISIBLE (-25 10275);
FORCEPROP 0 LAST CDS_LOCATION U13
J 0
(-375 11025);
DISPLAY 1.021277 (-375 11025);
DISPLAY INVISIBLE (-375 11025);
FORCEPROP 0 LAST $SEC 2
J 0
(-375 11025);
DISPLAY 0.680851 (-375 11025);
PAINT MONO (-375 11025);
DISPLAY INVISIBLE (-375 11025);
FORCEPROP 0 LAST CDS_SEC 2
J 0
(-375 11025);
DISPLAY 1.021277 (-375 11025);
DISPLAY INVISIBLE (-375 11025);
FORCEADD UNIVERSAL_GND..1
(-4275 5125);
FORCEPROP 3 LASTPIN (-4275 5175) SIG_NAME GND\g
J 0
(-4265 5185);
DISPLAY 0.659574 (-4265 5185);
PAINT MONO (-4265 5185);
DISPLAY INVISIBLE (-4265 5185);
FORCEPROP 1 LAST HDL_POWER GND
J 1
(-4250 5050);
DISPLAY 0.872340 (-4250 5050);
PAINT GREEN (-4250 5050);
DISPLAY INVISIBLE (-4250 5050);
FORCEPROP 1 LAST PATH I294
J 0
(-4200 5125);
DISPLAY 0.872340 (-4200 5125);
PAINT AQUA (-4200 5125);
DISPLAY INVISIBLE (-4200 5125);
FORCEPROP 2 LAST CDS_LIB logical_power
J 0
(-4275 5125);
DISPLAY INVISIBLE (-4275 5125);
FORCEADD UNIVERSAL_GND..1
(-5175 5125);
FORCEPROP 3 LASTPIN (-5175 5175) SIG_NAME GND\g
J 0
(-5165 5185);
DISPLAY 0.659574 (-5165 5185);
PAINT MONO (-5165 5185);
DISPLAY INVISIBLE (-5165 5185);
FORCEPROP 1 LAST HDL_POWER GND
J 1
(-5150 5050);
DISPLAY 0.872340 (-5150 5050);
PAINT GREEN (-5150 5050);
DISPLAY INVISIBLE (-5150 5050);
FORCEPROP 1 LAST PATH I295
J 0
(-5100 5125);
DISPLAY 0.872340 (-5100 5125);
PAINT AQUA (-5100 5125);
DISPLAY INVISIBLE (-5100 5125);
FORCEPROP 2 LAST CDS_LIB logical_power
J 0
(-5175 5125);
DISPLAY INVISIBLE (-5175 5125);
FORCEADD UNIVERSAL_GND..1
(675 5825);
FORCEPROP 3 LASTPIN (675 5875) SIG_NAME GND\g
J 0
(685 5885);
DISPLAY 0.659574 (685 5885);
PAINT MONO (685 5885);
DISPLAY INVISIBLE (685 5885);
FORCEPROP 2 LAST CDS_LIB logical_power
J 0
(675 5825);
DISPLAY INVISIBLE (675 5825);
FORCEPROP 1 LAST PATH I301
J 0
(750 5825);
DISPLAY 0.872340 (750 5825);
PAINT AQUA (750 5825);
DISPLAY INVISIBLE (750 5825);
FORCEPROP 1 LAST HDL_POWER GND
J 1
(700 5750);
DISPLAY 0.872340 (700 5750);
PAINT GREEN (700 5750);
DISPLAY INVISIBLE (700 5750);
FORCEADD UNIVERSAL_GND..1
(-5625 9400);
FORCEPROP 3 LASTPIN (-5625 9450) SIG_NAME GND\g
J 0
(-5615 9460);
DISPLAY 0.659574 (-5615 9460);
PAINT MONO (-5615 9460);
DISPLAY INVISIBLE (-5615 9460);
FORCEPROP 1 LAST HDL_POWER GND
J 1
(-5600 9325);
DISPLAY 0.872340 (-5600 9325);
PAINT GREEN (-5600 9325);
DISPLAY INVISIBLE (-5600 9325);
FORCEPROP 1 LAST PATH I302
J 0
(-5550 9400);
DISPLAY 0.872340 (-5550 9400);
PAINT AQUA (-5550 9400);
DISPLAY INVISIBLE (-5550 9400);
FORCEPROP 2 LAST CDS_LIB logical_power
J 0
(-5625 9400);
DISPLAY INVISIBLE (-5625 9400);
FORCEADD Q_RES..2
R 2
(-4575 6750);
FORCEPROP 1 LAST PART_NUMBER CS31002FB08
J 2
(-4615 6625);
DISPLAY 0.638298 (-4615 6625);
DISPLAY INVISIBLE (-4615 6625);
FORCEPROP 1 LAST TOLERANCE 1%
J 2
(-4620 6775);
DISPLAY 0.638298 (-4620 6775);
FORCEPROP 1 LAST WATTAGE 1/16W
J 2
(-4615 6725);
DISPLAY 0.638298 (-4615 6725);
FORCEPROP 1 LAST VALUE 10K
J 2
(-4620 6825);
DISPLAY 0.638298 (-4620 6825);
FORCEPROP 1 LAST MATERIAL CHIP
J 2
(-4615 6675);
DISPLAY 0.638298 (-4615 6675);
FORCEPROP 1 LAST PACK_TYPE 0402LF
J 2
(-4615 6575);
DISPLAY 0.638298 (-4615 6575);
FORCEPROP 1 LAST $LOCATION R1958
J 2
(-4620 6875);
DISPLAY 0.638298 (-4620 6875);
FORCEPROP 1 LASTPIN (-4575 6850) $PN 1
J 2
(-4580 6812);
DISPLAY 0.787234 (-4580 6812);
PAINT MONO (-4580 6812);
FORCEPROP 1 LASTPIN (-4575 6650) $PN 2
J 2
(-4580 6660);
DISPLAY 0.787234 (-4580 6660);
PAINT MONO (-4580 6660);
FORCEPROP 1 LAST PATH I303
J 2
(-4625 6925);
DISPLAY 0.978723 (-4625 6925);
PAINT WHITE (-4625 6925);
DISPLAY INVISIBLE (-4625 6925);
FORCEPROP 2 LAST CDS_LIB pure_quanta
J 2
(-4575 6750);
DISPLAY INVISIBLE (-4575 6750);
FORCEPROP 0 LAST CDS_LOCATION R1958
J 0
(-4600 6925);
DISPLAY 1.021277 (-4600 6925);
DISPLAY INVISIBLE (-4600 6925);
FORCEPROP 0 LAST $SEC 1
J 0
(-4600 6925);
DISPLAY 0.680851 (-4600 6925);
PAINT MONO (-4600 6925);
DISPLAY INVISIBLE (-4600 6925);
FORCEPROP 0 LAST CDS_SEC 1
J 0
(-4600 6925);
DISPLAY 1.021277 (-4600 6925);
DISPLAY INVISIBLE (-4600 6925);
FORCEADD UNIVERSAL_POWER..1
(-4575 6975);
FORCEPROP 3 LASTPIN (-4575 6925) SIG_NAME P3V3_AUX\g
J 0
(-4565 6935);
DISPLAY 0.659574 (-4565 6935);
PAINT MONO (-4565 6935);
DISPLAY INVISIBLE (-4565 6935);
FORCEPROP 1 LAST HDL_POWER P3V3_AUX
J 1
(-4575 7025);
DISPLAY 0.872340 (-4575 7025);
PAINT GREEN (-4575 7025);
FORCEPROP 1 LAST PATH I304
J 0
(-4525 7000);
DISPLAY 0.872340 (-4525 7000);
PAINT AQUA (-4525 7000);
DISPLAY INVISIBLE (-4525 7000);
FORCEPROP 2 LAST CDS_LIB logical_power
J 0
(-4575 6975);
DISPLAY INVISIBLE (-4575 6975);
FORCEADD OFFPAGE..1
(-2100 6975);
FORCEPROP 2 LAST $XR0 208 
J 0
(-2352 6975);
DISPLAY 0.638298 (-2352 6975);
PAINT MONO (-2352 6975);
FORCEPROP 2 LAST PATH I330
J 0
(-2050 7050);
DISPLAY 1.021277 (-2050 7050);
DISPLAY INVISIBLE (-2050 7050);
FORCEPROP 1 LAST OFFPAGE TRUE
J 0
(-1775 6850);
DISPLAY 0.872340 (-1775 6850);
PAINT GREEN (-1775 6850);
DISPLAY INVISIBLE (-1775 6850);
FORCEPROP 1 LAST COMMENT_BODY TRUE
J 0
(-1975 6875);
DISPLAY 0.872340 (-1975 6875);
PAINT GREEN (-1975 6875);
DISPLAY INVISIBLE (-1975 6875);
FORCEPROP 2 LAST CDS_LIB standard
J 0
(-2100 6975);
DISPLAY INVISIBLE (-2100 6975);
FORCEADD Q_RES..1
(-2650 6925);
FORCEPROP 1 LAST PART_NUMBER CS31002FB08
J 0
(-2750 6975);
DISPLAY 0.510638 (-2750 6975);
DISPLAY INVISIBLE (-2750 6975);
FORCEPROP 1 LAST TOLERANCE 1%
J 0
(-2450 6925);
DISPLAY 0.510638 (-2450 6925);
FORCEPROP 1 LAST MATERIAL CHIP
J 0
(-2375 6925);
DISPLAY 0.510638 (-2375 6925);
FORCEPROP 1 LAST VALUE 10K
J 2
(-2475 6925);
DISPLAY 0.510638 (-2475 6925);
FORCEPROP 1 LAST $LOCATION R3638
J 0
(-2900 6925);
DISPLAY 0.638298 (-2900 6925);
FORCEPROP 1 LASTPIN (-2750 6925) $PN 1
J 0
(-2738 6937);
DISPLAY 0.787234 (-2738 6937);
PAINT MONO (-2738 6937);
FORCEPROP 1 LASTPIN (-2550 6925) $PN 2
J 0
(-2588 6937);
DISPLAY 0.787234 (-2588 6937);
PAINT MONO (-2588 6937);
FORCEPROP 2 LAST CDS_LIB pure_quanta
J 0
(-2650 6925);
DISPLAY INVISIBLE (-2650 6925);
FORCEPROP 1 LAST PATH I378
J 0
(-2700 7075);
DISPLAY 0.978723 (-2700 7075);
PAINT WHITE (-2700 7075);
DISPLAY INVISIBLE (-2700 7075);
FORCEPROP 1 LAST PACK_TYPE 0402LF
J 0
(-2750 7000);
DISPLAY 0.510638 (-2750 7000);
DISPLAY INVISIBLE (-2750 7000);
FORCEPROP 1 LAST WATTAGE 1/16W
J 2
(-2450 7000);
DISPLAY 0.510638 (-2450 7000);
DISPLAY INVISIBLE (-2450 7000);
FORCEPROP 0 LAST CDS_LOCATION R3638
J 0
(-2775 6975);
DISPLAY 1.021277 (-2775 6975);
DISPLAY INVISIBLE (-2775 6975);
FORCEPROP 0 LAST $SEC 1
J 0
(-2775 6975);
DISPLAY 0.680851 (-2775 6975);
PAINT MONO (-2775 6975);
DISPLAY INVISIBLE (-2775 6975);
FORCEPROP 0 LAST CDS_SEC 1
J 0
(-2775 6975);
DISPLAY 1.021277 (-2775 6975);
DISPLAY INVISIBLE (-2775 6975);
FORCEADD Q_RES..1
(-2650 6875);
FORCEPROP 1 LAST PART_NUMBER CS31002FB08
J 0
(-2750 6925);
DISPLAY 0.510638 (-2750 6925);
DISPLAY INVISIBLE (-2750 6925);
FORCEPROP 1 LAST TOLERANCE 1%
J 0
(-2450 6875);
DISPLAY 0.510638 (-2450 6875);
FORCEPROP 1 LAST VALUE 10K
J 2
(-2475 6875);
DISPLAY 0.510638 (-2475 6875);
FORCEPROP 1 LAST MATERIAL CHIP
J 0
(-2375 6875);
DISPLAY 0.510638 (-2375 6875);
FORCEPROP 1 LAST $LOCATION R3639
J 0
(-2900 6875);
DISPLAY 0.638298 (-2900 6875);
FORCEPROP 1 LASTPIN (-2750 6875) $PN 1
J 0
(-2738 6887);
DISPLAY 0.787234 (-2738 6887);
PAINT MONO (-2738 6887);
FORCEPROP 1 LASTPIN (-2550 6875) $PN 2
J 0
(-2588 6887);
DISPLAY 0.787234 (-2588 6887);
PAINT MONO (-2588 6887);
FORCEPROP 2 LAST CDS_LIB pure_quanta
J 0
(-2650 6875);
DISPLAY INVISIBLE (-2650 6875);
FORCEPROP 1 LAST PATH I379
J 0
(-2700 7025);
DISPLAY 0.978723 (-2700 7025);
PAINT WHITE (-2700 7025);
DISPLAY INVISIBLE (-2700 7025);
FORCEPROP 1 LAST PACK_TYPE 0402LF
J 0
(-2750 6950);
DISPLAY 0.510638 (-2750 6950);
DISPLAY INVISIBLE (-2750 6950);
FORCEPROP 1 LAST WATTAGE 1/16W
J 2
(-2450 6950);
DISPLAY 0.510638 (-2450 6950);
DISPLAY INVISIBLE (-2450 6950);
FORCEPROP 0 LAST CDS_LOCATION R3639
J 0
(-2775 6925);
DISPLAY 1.021277 (-2775 6925);
DISPLAY INVISIBLE (-2775 6925);
FORCEPROP 0 LAST $SEC 1
J 0
(-2775 6925);
DISPLAY 0.680851 (-2775 6925);
PAINT MONO (-2775 6925);
DISPLAY INVISIBLE (-2775 6925);
FORCEPROP 0 LAST CDS_SEC 1
J 0
(-2775 6925);
DISPLAY 1.021277 (-2775 6925);
DISPLAY INVISIBLE (-2775 6925);
FORCEADD Q_RES..1
(-2650 6825);
FORCEPROP 1 LAST PART_NUMBER CS31002FB08
J 0
(-2750 6875);
DISPLAY 0.510638 (-2750 6875);
DISPLAY INVISIBLE (-2750 6875);
FORCEPROP 1 LAST TOLERANCE 1%
J 0
(-2450 6825);
DISPLAY 0.510638 (-2450 6825);
FORCEPROP 1 LAST VALUE 10K
J 2
(-2475 6825);
DISPLAY 0.510638 (-2475 6825);
FORCEPROP 1 LAST MATERIAL CHIP
J 0
(-2375 6825);
DISPLAY 0.510638 (-2375 6825);
FORCEPROP 1 LAST $LOCATION R3640
J 0
(-2900 6825);
DISPLAY 0.638298 (-2900 6825);
FORCEPROP 1 LASTPIN (-2750 6825) $PN 1
J 0
(-2738 6837);
DISPLAY 0.787234 (-2738 6837);
PAINT MONO (-2738 6837);
FORCEPROP 1 LASTPIN (-2550 6825) $PN 2
J 0
(-2588 6837);
DISPLAY 0.787234 (-2588 6837);
PAINT MONO (-2588 6837);
FORCEPROP 2 LAST CDS_LIB pure_quanta
J 0
(-2650 6825);
DISPLAY INVISIBLE (-2650 6825);
FORCEPROP 1 LAST PATH I380
J 0
(-2700 6975);
DISPLAY 0.978723 (-2700 6975);
PAINT WHITE (-2700 6975);
DISPLAY INVISIBLE (-2700 6975);
FORCEPROP 1 LAST PACK_TYPE 0402LF
J 0
(-2750 6900);
DISPLAY 0.510638 (-2750 6900);
DISPLAY INVISIBLE (-2750 6900);
FORCEPROP 1 LAST WATTAGE 1/16W
J 2
(-2450 6900);
DISPLAY 0.510638 (-2450 6900);
DISPLAY INVISIBLE (-2450 6900);
FORCEPROP 0 LAST CDS_LOCATION R3640
J 0
(-2775 6875);
DISPLAY 1.021277 (-2775 6875);
DISPLAY INVISIBLE (-2775 6875);
FORCEPROP 0 LAST $SEC 1
J 0
(-2775 6875);
DISPLAY 0.680851 (-2775 6875);
PAINT MONO (-2775 6875);
DISPLAY INVISIBLE (-2775 6875);
FORCEPROP 0 LAST CDS_SEC 1
J 0
(-2775 6875);
DISPLAY 1.021277 (-2775 6875);
DISPLAY INVISIBLE (-2775 6875);
FORCEADD Q_RES..1
(-2650 6775);
FORCEPROP 1 LAST PART_NUMBER CS31002FB08
J 0
(-2750 6825);
DISPLAY 0.510638 (-2750 6825);
DISPLAY INVISIBLE (-2750 6825);
FORCEPROP 1 LAST VALUE 10K
J 2
(-2475 6775);
DISPLAY 0.510638 (-2475 6775);
FORCEPROP 1 LAST TOLERANCE 1%
J 0
(-2450 6775);
DISPLAY 0.510638 (-2450 6775);
FORCEPROP 1 LAST MATERIAL CHIP
J 0
(-2375 6775);
DISPLAY 0.510638 (-2375 6775);
FORCEPROP 1 LAST $LOCATION R3641
J 0
(-2900 6775);
DISPLAY 0.638298 (-2900 6775);
FORCEPROP 1 LASTPIN (-2750 6775) $PN 1
J 0
(-2738 6787);
DISPLAY 0.787234 (-2738 6787);
PAINT MONO (-2738 6787);
FORCEPROP 1 LASTPIN (-2550 6775) $PN 2
J 0
(-2588 6787);
DISPLAY 0.787234 (-2588 6787);
PAINT MONO (-2588 6787);
FORCEPROP 2 LAST CDS_LIB pure_quanta
J 0
(-2650 6775);
DISPLAY INVISIBLE (-2650 6775);
FORCEPROP 1 LAST PATH I381
J 0
(-2700 6925);
DISPLAY 0.978723 (-2700 6925);
PAINT WHITE (-2700 6925);
DISPLAY INVISIBLE (-2700 6925);
FORCEPROP 1 LAST PACK_TYPE 0402LF
J 0
(-2750 6850);
DISPLAY 0.510638 (-2750 6850);
DISPLAY INVISIBLE (-2750 6850);
FORCEPROP 1 LAST WATTAGE 1/16W
J 2
(-2450 6850);
DISPLAY 0.510638 (-2450 6850);
DISPLAY INVISIBLE (-2450 6850);
FORCEPROP 0 LAST CDS_LOCATION R3641
J 0
(-2775 6825);
DISPLAY 1.021277 (-2775 6825);
DISPLAY INVISIBLE (-2775 6825);
FORCEPROP 0 LAST $SEC 1
J 0
(-2775 6825);
DISPLAY 0.680851 (-2775 6825);
PAINT MONO (-2775 6825);
DISPLAY INVISIBLE (-2775 6825);
FORCEPROP 0 LAST CDS_SEC 1
J 0
(-2775 6825);
DISPLAY 1.021277 (-2775 6825);
DISPLAY INVISIBLE (-2775 6825);
FORCEADD Q_RES..1
(-2650 6725);
FORCEPROP 1 LAST PART_NUMBER CS31002FB08
J 0
(-2750 6775);
DISPLAY 0.510638 (-2750 6775);
DISPLAY INVISIBLE (-2750 6775);
FORCEPROP 1 LAST VALUE 10K
J 2
(-2475 6725);
DISPLAY 0.510638 (-2475 6725);
FORCEPROP 1 LAST MATERIAL CHIP
J 0
(-2375 6725);
DISPLAY 0.510638 (-2375 6725);
FORCEPROP 1 LAST TOLERANCE 1%
J 0
(-2450 6725);
DISPLAY 0.510638 (-2450 6725);
FORCEPROP 1 LAST $LOCATION R3642
J 0
(-2900 6725);
DISPLAY 0.638298 (-2900 6725);
FORCEPROP 1 LASTPIN (-2750 6725) $PN 1
J 0
(-2738 6737);
DISPLAY 0.787234 (-2738 6737);
PAINT MONO (-2738 6737);
FORCEPROP 1 LASTPIN (-2550 6725) $PN 2
J 0
(-2588 6737);
DISPLAY 0.787234 (-2588 6737);
PAINT MONO (-2588 6737);
FORCEPROP 2 LAST CDS_LIB pure_quanta
J 0
(-2650 6725);
DISPLAY INVISIBLE (-2650 6725);
FORCEPROP 1 LAST PATH I382
J 0
(-2700 6875);
DISPLAY 0.978723 (-2700 6875);
PAINT WHITE (-2700 6875);
DISPLAY INVISIBLE (-2700 6875);
FORCEPROP 1 LAST PACK_TYPE 0402LF
J 0
(-2750 6800);
DISPLAY 0.510638 (-2750 6800);
DISPLAY INVISIBLE (-2750 6800);
FORCEPROP 1 LAST WATTAGE 1/16W
J 2
(-2450 6800);
DISPLAY 0.510638 (-2450 6800);
DISPLAY INVISIBLE (-2450 6800);
FORCEPROP 0 LAST CDS_LOCATION R3642
J 0
(-2775 6775);
DISPLAY 1.021277 (-2775 6775);
DISPLAY INVISIBLE (-2775 6775);
FORCEPROP 0 LAST $SEC 1
J 0
(-2775 6775);
DISPLAY 0.680851 (-2775 6775);
PAINT MONO (-2775 6775);
DISPLAY INVISIBLE (-2775 6775);
FORCEPROP 0 LAST CDS_SEC 1
J 0
(-2775 6775);
DISPLAY 1.021277 (-2775 6775);
DISPLAY INVISIBLE (-2775 6775);
FORCEADD Q_RES..1
(-2650 6675);
FORCEPROP 1 LAST PART_NUMBER CS31002FB08
J 0
(-2750 6725);
DISPLAY 0.510638 (-2750 6725);
DISPLAY INVISIBLE (-2750 6725);
FORCEPROP 1 LAST VALUE 10K
J 2
(-2475 6675);
DISPLAY 0.510638 (-2475 6675);
FORCEPROP 1 LAST MATERIAL CHIP
J 0
(-2375 6675);
DISPLAY 0.510638 (-2375 6675);
FORCEPROP 1 LAST TOLERANCE 1%
J 0
(-2450 6675);
DISPLAY 0.510638 (-2450 6675);
FORCEPROP 1 LAST $LOCATION R3643
J 0
(-2900 6675);
DISPLAY 0.638298 (-2900 6675);
FORCEPROP 1 LASTPIN (-2750 6675) $PN 1
J 0
(-2738 6687);
DISPLAY 0.787234 (-2738 6687);
PAINT MONO (-2738 6687);
FORCEPROP 1 LASTPIN (-2550 6675) $PN 2
J 0
(-2588 6687);
DISPLAY 0.787234 (-2588 6687);
PAINT MONO (-2588 6687);
FORCEPROP 2 LAST CDS_LIB pure_quanta
J 0
(-2650 6675);
DISPLAY INVISIBLE (-2650 6675);
FORCEPROP 1 LAST PATH I383
J 0
(-2700 6825);
DISPLAY 0.978723 (-2700 6825);
PAINT WHITE (-2700 6825);
DISPLAY INVISIBLE (-2700 6825);
FORCEPROP 1 LAST PACK_TYPE 0402LF
J 0
(-2750 6750);
DISPLAY 0.510638 (-2750 6750);
DISPLAY INVISIBLE (-2750 6750);
FORCEPROP 1 LAST WATTAGE 1/16W
J 2
(-2450 6750);
DISPLAY 0.510638 (-2450 6750);
DISPLAY INVISIBLE (-2450 6750);
FORCEPROP 0 LAST CDS_LOCATION R3643
J 0
(-2775 6725);
DISPLAY 1.021277 (-2775 6725);
DISPLAY INVISIBLE (-2775 6725);
FORCEPROP 0 LAST $SEC 1
J 0
(-2775 6725);
DISPLAY 0.680851 (-2775 6725);
PAINT MONO (-2775 6725);
DISPLAY INVISIBLE (-2775 6725);
FORCEPROP 0 LAST CDS_SEC 1
J 0
(-2775 6725);
DISPLAY 1.021277 (-2775 6725);
DISPLAY INVISIBLE (-2775 6725);
FORCEADD UNIVERSAL_POWER..1
(-3175 7125);
FORCEPROP 3 LASTPIN (-3175 7075) SIG_NAME P3V3_AUX\g
J 0
(-3165 7085);
DISPLAY 0.659574 (-3165 7085);
PAINT MONO (-3165 7085);
DISPLAY INVISIBLE (-3165 7085);
FORCEPROP 1 LAST HDL_POWER P3V3_AUX
J 1
(-3175 7175);
DISPLAY 0.872340 (-3175 7175);
PAINT GREEN (-3175 7175);
FORCEPROP 1 LAST PATH I385
J 0
(-3125 7150);
DISPLAY 0.872340 (-3125 7150);
PAINT AQUA (-3125 7150);
DISPLAY INVISIBLE (-3125 7150);
FORCEPROP 2 LAST CDS_LIB logical_power
J 0
(-3175 7125);
DISPLAY INVISIBLE (-3175 7125);
FORCEADD Q_XTAL_4P_13BI_24GND..1
(-4725 5725);
FORCEPROP 1 LAST PART_NUMBER BG6250000F0
J 0
(-4858 6000);
DISPLAY 0.723404 (-4858 6000);
PAINT GREEN (-4858 6000);
DISPLAY INVISIBLE (-4858 6000);
FORCEPROP 2 LAST PART_TYPE SMLF
J 0
(-4850 6175);
DISPLAY 1.021277 (-4850 6175);
FORCEPROP 2 LAST VALUE 25MHZ
J 0
(-4850 6125);
DISPLAY 1.021277 (-4850 6125);
FORCEPROP 1 LAST MATERIAL MISC
J 0
(-4858 5904);
DISPLAY 0.723404 (-4858 5904);
PAINT GREEN (-4858 5904);
FORCEPROP 1 LAST LOCATION Y2
J 0
(-4875 6075);
DISPLAY 0.723404 (-4875 6075);
PAINT GREEN (-4875 6075);
FORCEPROP 0 LASTPIN (-5000 5600) $PN 2
J 2
(-5010 5610);
DISPLAY 0.680851 (-5010 5610);
PAINT MONO (-5010 5610);
FORCEPROP 0 LASTPIN (-4450 5600) $PN 4
J 0
(-4440 5610);
DISPLAY 0.680851 (-4440 5610);
PAINT MONO (-4440 5610);
FORCEPROP 0 LASTPIN (-5000 5800) $PN 1
J 2
(-5010 5810);
DISPLAY 0.680851 (-5010 5810);
PAINT MONO (-5010 5810);
FORCEPROP 0 LASTPIN (-4450 5800) $PN 3
J 0
(-4440 5810);
DISPLAY 0.680851 (-4440 5810);
PAINT MONO (-4440 5810);
FORCEPROP 2 LAST CDS_LIB pure_quanta
J 0
(-4725 5725);
DISPLAY INVISIBLE (-4725 5725);
FORCEPROP 1 LAST CDS_LMAN_SYM_OUTLINE -125,175,125,-175
J 0
(-4725 5725);
DISPLAY 0.468085 (-4725 5725);
PAINT GREEN (-4725 5725);
DISPLAY INVISIBLE (-4725 5725);
FORCEPROP 1 LAST PATH I391
J 0
(-4600 5550);
DISPLAY 0.723404 (-4600 5550);
PAINT GREEN (-4600 5550);
DISPLAY INVISIBLE (-4600 5550);
FORCEPROP 1 LAST PIN_NAMES_ROTATE True
J 0
(-4725 5725);
DISPLAY 0.489362 (-4725 5725);
PAINT GREEN (-4725 5725);
DISPLAY INVISIBLE (-4725 5725);
FORCEPROP 0 LAST $SEC 1
J 0
(-4850 6225);
DISPLAY 0.680851 (-4850 6225);
PAINT MONO (-4850 6225);
DISPLAY INVISIBLE (-4850 6225);
FORCEPROP 0 LAST CDS_SEC 1
J 0
(-4850 6225);
DISPLAY 1.021277 (-4850 6225);
DISPLAY INVISIBLE (-4850 6225);
FORCEADD Q_RES..1
(-4150 6275);
FORCEPROP 1 LAST PART_NUMBER CS00002JB13
J 0
(-4025 6325);
DISPLAY 0.638298 (-4025 6325);
DISPLAY INVISIBLE (-4025 6325);
FORCEPROP 1 LAST WATTAGE 1/16W
J 2
(-3675 6375);
DISPLAY 0.638298 (-3675 6375);
FORCEPROP 1 LAST PACK_TYPE 0402LF
J 0
(-3750 6275);
DISPLAY 0.787234 (-3750 6275);
FORCEPROP 1 LAST VALUE 0
J 2
(-3875 6275);
DISPLAY 0.787234 (-3875 6275);
FORCEPROP 1 LAST TOLERANCE 5%
J 0
(-3850 6275);
DISPLAY 0.787234 (-3850 6275);
FORCEPROP 1 LAST MATERIAL CHIP
J 0
(-4025 6375);
DISPLAY 0.638298 (-4025 6375);
FORCEPROP 1 LAST LOCATION R1724
J 0
(-4350 6275);
DISPLAY 0.638298 (-4350 6275);
FORCEPROP 1 LASTPIN (-4250 6275) $PN 1
J 0
(-4238 6287);
DISPLAY 0.787234 (-4238 6287);
PAINT MONO (-4238 6287);
FORCEPROP 1 LASTPIN (-4050 6275) $PN 2
J 0
(-4088 6287);
DISPLAY 0.787234 (-4088 6287);
PAINT MONO (-4088 6287);
FORCEPROP 1 LAST PATH I392
J 0
(-4200 6425);
DISPLAY 0.978723 (-4200 6425);
PAINT WHITE (-4200 6425);
DISPLAY INVISIBLE (-4200 6425);
FORCEPROP 2 LAST CDS_LIB pure_quanta
J 0
(-4150 6275);
DISPLAY INVISIBLE (-4150 6275);
FORCEPROP 0 LAST $SEC 1
J 0
(-3675 6425);
DISPLAY 0.680851 (-3675 6425);
PAINT MONO (-3675 6425);
DISPLAY INVISIBLE (-3675 6425);
FORCEPROP 0 LAST CDS_SEC 1
J 0
(-3675 6425);
DISPLAY 1.021277 (-3675 6425);
DISPLAY INVISIBLE (-3675 6425);
FORCEADD Q_CAP..1
(-5175 5475);
FORCEPROP 1 LAST PART_NUMBER CH-8216TB09
J 2
(-5250 5300);
DISPLAY 0.978723 (-5250 5300);
DISPLAY INVISIBLE (-5250 5300);
FORCEPROP 1 LAST VALUE 8.2PF
J 2
(-5250 5500);
DISPLAY 0.978723 (-5250 5500);
FORCEPROP 1 LAST MATERIAL NP0
J 2
(-5250 5350);
DISPLAY 0.978723 (-5250 5350);
FORCEPROP 1 LAST PACK_TYPE C0402
J 2
(-5250 5250);
DISPLAY 0.978723 (-5250 5250);
FORCEPROP 1 LAST VOLTAGE 50V
J 2
(-5250 5450);
DISPLAY 0.978723 (-5250 5450);
FORCEPROP 1 LAST TOLERANCE 0.1P
J 2
(-5250 5400);
DISPLAY 0.978723 (-5250 5400);
FORCEPROP 1 LAST LOCATION C2036
J 2
(-5250 5550);
DISPLAY 0.978723 (-5250 5550);
FORCEPROP 1 LASTPIN (-5175 5575) $PN 1
J 0
(-5165 5555);
DISPLAY 0.787234 (-5165 5555);
PAINT MONO (-5165 5555);
FORCEPROP 1 LASTPIN (-5175 5375) $PN 2
J 0
(-5165 5355);
DISPLAY 0.787234 (-5165 5355);
PAINT MONO (-5165 5355);
FORCEPROP 2 LAST CDS_LIB pure_quanta
J 0
(-5175 5475);
DISPLAY INVISIBLE (-5175 5475);
FORCEPROP 1 LAST PATH I393
J 0
(-5125 5625);
DISPLAY 0.978723 (-5125 5625);
PAINT WHITE (-5125 5625);
DISPLAY INVISIBLE (-5125 5625);
FORCEPROP 0 LAST $SEC 1
J 0
(-5250 5600);
DISPLAY 0.680851 (-5250 5600);
PAINT MONO (-5250 5600);
DISPLAY INVISIBLE (-5250 5600);
FORCEPROP 0 LAST CDS_SEC 1
J 0
(-5250 5600);
DISPLAY 1.021277 (-5250 5600);
DISPLAY INVISIBLE (-5250 5600);
FORCEADD Q_CAP..1
(-4275 5475);
FORCEPROP 1 LAST PART_NUMBER CH-8216TB09
J 0
(-4225 5275);
DISPLAY 0.978723 (-4225 5275);
DISPLAY INVISIBLE (-4225 5275);
FORCEPROP 1 LAST PACK_TYPE C0402
J 0
(-4225 5225);
DISPLAY 0.978723 (-4225 5225);
FORCEPROP 1 LAST MATERIAL NP0
J 0
(-4225 5325);
DISPLAY 0.978723 (-4225 5325);
FORCEPROP 1 LAST VOLTAGE 50V
J 0
(-4225 5425);
DISPLAY 0.978723 (-4225 5425);
FORCEPROP 1 LAST TOLERANCE 0.1P
J 0
(-4225 5375);
DISPLAY 0.978723 (-4225 5375);
FORCEPROP 1 LAST VALUE 8.2PF
J 0
(-4225 5475);
DISPLAY 0.978723 (-4225 5475);
FORCEPROP 1 LAST LOCATION C2037
J 0
(-4225 5525);
DISPLAY 0.978723 (-4225 5525);
FORCEPROP 1 LASTPIN (-4275 5575) $PN 1
J 0
(-4265 5555);
DISPLAY 0.787234 (-4265 5555);
PAINT MONO (-4265 5555);
FORCEPROP 1 LASTPIN (-4275 5375) $PN 2
J 0
(-4265 5355);
DISPLAY 0.787234 (-4265 5355);
PAINT MONO (-4265 5355);
FORCEPROP 2 LAST CDS_LIB pure_quanta
J 0
(-4275 5475);
DISPLAY INVISIBLE (-4275 5475);
FORCEPROP 1 LAST PATH I394
J 0
(-4225 5625);
DISPLAY 0.978723 (-4225 5625);
PAINT WHITE (-4225 5625);
DISPLAY INVISIBLE (-4225 5625);
FORCEPROP 0 LAST $SEC 1
J 0
(-4225 5575);
DISPLAY 0.680851 (-4225 5575);
PAINT MONO (-4225 5575);
DISPLAY INVISIBLE (-4225 5575);
FORCEPROP 0 LAST CDS_SEC 1
J 0
(-4225 5575);
DISPLAY 1.021277 (-4225 5575);
DISPLAY INVISIBLE (-4225 5575);
FORCEADD OFFPAGE..2
(1675 8425);
FORCEPROP 2 LAST $XR0 206 
J 0
(1864 8425);
DISPLAY 0.638298 (1864 8425);
PAINT MONO (1864 8425);
FORCEPROP 2 LAST CDS_LIB standard
J 0
(1675 8425);
PAINT MONO (1675 8425);
DISPLAY INVISIBLE (1675 8425);
FORCEPROP 2 LAST PATH I99
J 0
(1850 8500);
DISPLAY 1.021277 (1850 8500);
DISPLAY INVISIBLE (1850 8500);
FORCEPROP 1 LAST COMMENT_BODY TRUE
J 0
(1630 8330);
DISPLAY 0.872340 (1630 8330);
PAINT GREEN (1630 8330);
DISPLAY INVISIBLE (1630 8330);
FORCEPROP 1 LAST OFFPAGE TRUE
J 0
(2000 8300);
DISPLAY 0.872340 (2000 8300);
PAINT GREEN (2000 8300);
DISPLAY INVISIBLE (2000 8300);
FORCEADD QUANTA_TITLE_BLOCK_C..1
(3300 4875);
FORCEPROP 0 LAST CDS_CON_LAST_MODIFIED Fri Aug 25 14:03:24 2023
J 0
(1415 4890);
PAINT MONO (1415 4890);
DISPLAY INVISIBLE (1415 4890);
FORCEPROP 1 LAST CUSTOM_TXT_CDS <CON_LAST_MODIFIED>
J 0
(1415 4890);
DISPLAY 0.978723 (1415 4890);
FORCEPROP 2 LAST CUSTOM_TXT_CDS <XR_PAGE_TITLE>
J 0
(-4590 10125);
DISPLAY 0.638298 (-4590 10125);
PAINT PINK (-4590 10125);
DISPLAY INVISIBLE (-4590 10125);
FORCEPROP 2 LAST CUSTOM_TXT_CDS <NAME_1>
J 0
(225 5025);
FORCEPROP 2 LAST CUSTOM_TXT_CDS <NAME_2>
J 0
(225 4925);
FORCEPROP 2 LAST CUSTOM_TXT_CDS <Q_NUMBER>
J 0
(1897 4978);
DISPLAY 1.212766 (1897 4978);
FORCEPROP 2 LAST CUSTOM_TXT_CDS <Q_PROJ>
J 0
(1150 4975);
DISPLAY 1.212766 (1150 4975);
FORCEPROP 2 LAST CUSTOM_TXT_CDS <CON_PAGE_NUM> OF <CON_TOTAL_PAGES>
J 0
(2854 4893);
DISPLAY 0.978723 (2854 4893);
FORCEPROP 2 LAST CUSTOM_TXT_CDS <Q_REV>
J 0
(3116 4978);
DISPLAY 1.212766 (3116 4978);
FORCEPROP 1 LAST Q_TITLE CLK- CK440Q CLK GEN
J 0
(-6041 4901);
DISPLAY 1.957447 (-6041 4901);
PAINT GREEN (-6041 4901);
FORCEPROP 1 LAST Q_DEPT 
J 1
(-463 4924);
DISPLAY 1.957447 (-463 4924);
PAINT GREEN (-463 4924);
FORCEPROP 2 LAST CDS_XR_PAGE_TITLE CR-208 : @S9S_MB_2U_LIB.S9S_MB_2U(SCH_1):PAGE208
J 0
(-4590 10125);
DISPLAY 0.638298 (-4590 10125);
PAINT PINK (-4590 10125);
DISPLAY INVISIBLE (-4590 10125);
FORCEPROP 1 LAST COMMENT_BODY TRUE
J 0
(3312 4862);
DISPLAY 0.978723 (3312 4862);
PAINT GREEN (3312 4862);
DISPLAY INVISIBLE (3312 4862);
FORCEPROP 2 LAST PAGE_BORDER TRUE
J 0
(-4590 10125);
DISPLAY 0.638298 (-4590 10125);
PAINT PINK (-4590 10125);
DISPLAY INVISIBLE (-4590 10125);
FORCEPROP 1 LAST CDS_LMAN_SYM_OUTLINE -9475,6775,100,-125
J 0
(3300 4875);
DISPLAY 0.468085 (3300 4875);
PAINT GREEN (3300 4875);
DISPLAY INVISIBLE (3300 4875);
FORCEPROP 2 LAST CDS_LIB pure_quanta
J 0
(3300 4875);
PAINT MONO (3300 4875);
DISPLAY INVISIBLE (3300 4875);
FORCEADD DESIGN_NOTE..1
(2400 7775);
FORCEPROP 0 LAST S5 MXCK 100M:
J 0
(2200 7650);
DISPLAY 0.808511 (2200 7650);
PAINT SKYBLUE (2200 7650);
FORCEPROP 0 LAST S6 PORT 2: PCH
J 0
(2200 7550);
DISPLAY 0.808511 (2200 7550);
PAINT SKYBLUE (2200 7550);
FORCEPROP 0 LAST S7 PORT 4/5/7/8: OCP_SFF(CPU0)
J 0
(2200 7475);
DISPLAY 0.808511 (2200 7475);
PAINT SKYBLUE (2200 7475);
FORCEPROP 2 LAST CDS_LIB logical_power
J 0
(2400 7775);
DISPLAY INVISIBLE (2400 7775);
FORCEPROP 1 LAST COMMENT_BODY TRUE
J 0
(2425 7875);
DISPLAY 0.978723 (2425 7875);
DISPLAY INVISIBLE (2425 7875);
FORCEADD DNS..2
(-4400 10700);
PAINT RED (-4400 10700);
FORCEPROP 1 LAST COMMENT_BODY TRUE
R 1
J 0
(-4325 10475);
DISPLAY 0.872340 (-4325 10475);
PAINT GREEN (-4325 10475);
DISPLAY INVISIBLE (-4325 10475);
FORCEPROP 2 LAST CDS_LIB mstr_misc
J 0
(-4400 10700);
PAINT MONO (-4400 10700);
DISPLAY INVISIBLE (-4400 10700);
FORCEADD DNS..2
(-4400 9775);
PAINT RED (-4400 9775);
FORCEPROP 1 LAST COMMENT_BODY TRUE
R 1
J 0
(-4325 9550);
DISPLAY 0.872340 (-4325 9550);
PAINT GREEN (-4325 9550);
DISPLAY INVISIBLE (-4325 9550);
FORCEPROP 2 LAST CDS_LIB mstr_misc
J 0
(-4400 9775);
PAINT MONO (-4400 9775);
DISPLAY INVISIBLE (-4400 9775);
FORCEADD DNS..2
(-5350 10700);
PAINT RED (-5350 10700);
FORCEPROP 2 LAST CDS_LIB mstr_misc
J 0
(-5350 10700);
PAINT MONO (-5350 10700);
DISPLAY INVISIBLE (-5350 10700);
FORCEPROP 1 LAST COMMENT_BODY TRUE
R 1
J 0
(-5275 10475);
DISPLAY 0.872340 (-5275 10475);
PAINT GREEN (-5275 10475);
DISPLAY INVISIBLE (-5275 10475);
FORCEADD DNS..2
(-4675 10700);
PAINT RED (-4675 10700);
FORCEPROP 1 LAST COMMENT_BODY TRUE
R 1
J 0
(-4600 10475);
DISPLAY 0.872340 (-4600 10475);
PAINT GREEN (-4600 10475);
DISPLAY INVISIBLE (-4600 10475);
FORCEPROP 2 LAST CDS_LIB mstr_misc
J 0
(-4675 10700);
PAINT MONO (-4675 10700);
DISPLAY INVISIBLE (-4675 10700);
FORCEADD DNS..2
(-3150 10700);
PAINT RED (-3150 10700);
FORCEPROP 2 LAST CDS_LIB mstr_misc
J 0
(-3150 10700);
PAINT MONO (-3150 10700);
DISPLAY INVISIBLE (-3150 10700);
FORCEPROP 1 LAST COMMENT_BODY TRUE
R 1
J 0
(-3075 10475);
DISPLAY 0.872340 (-3075 10475);
PAINT GREEN (-3075 10475);
DISPLAY INVISIBLE (-3075 10475);
FORCEADD DESIGN_NOTE..1
(325 5675);
FORCEPROP 0 LAST S1 MXCK3/3# & MXCK6/6# & 100M6/6# WILL NOT USE DUE TO PINOUT LIMITATION
J 0
(125 5525);
DISPLAY 0.808511 (125 5525);
PAINT SKYBLUE (125 5525);
FORCEPROP 2 LAST CDS_LIB logical_power
J 0
(325 5675);
DISPLAY INVISIBLE (325 5675);
FORCEPROP 1 LAST COMMENT_BODY TRUE
J 0
(350 5775);
DISPLAY 0.978723 (350 5775);
DISPLAY INVISIBLE (350 5775);
FORCEADD DNS..2
(-1950 5750);
PAINT RED (-1950 5750);
FORCEPROP 1 LAST COMMENT_BODY TRUE
R 1
J 0
(-1875 5525);
DISPLAY 0.872340 (-1875 5525);
PAINT GREEN (-1875 5525);
DISPLAY INVISIBLE (-1875 5525);
FORCEPROP 2 LAST CDS_LIB mstr_misc
J 0
(-1950 5750);
PAINT MONO (-1950 5750);
DISPLAY INVISIBLE (-1950 5750);
FORCEADD DNS..2
(-5625 10700);
PAINT RED (-5625 10700);
FORCEPROP 1 LAST COMMENT_BODY TRUE
R 1
J 0
(-5550 10475);
DISPLAY 0.872340 (-5550 10475);
PAINT GREEN (-5550 10475);
DISPLAY INVISIBLE (-5550 10475);
FORCEPROP 2 LAST CDS_LIB mstr_misc
J 0
(-5625 10700);
PAINT MONO (-5625 10700);
DISPLAY INVISIBLE (-5625 10700);
FORCEADD DESIGN_NOTE..1
(100 9125);
FORCEPROP 0 LAST S1 SMBUS ADDRESS: 0XD2
J 0
(-100 8975);
DISPLAY 1.595745 (-100 8975);
PAINT SKYBLUE (-100 8975);
FORCEPROP 2 LAST CDS_LIB logical_power
J 0
(100 9125);
PAINT MONO (100 9125);
DISPLAY INVISIBLE (100 9125);
FORCEPROP 1 LAST COMMENT_BODY TRUE
J 0
(125 9225);
DISPLAY 0.978723 (125 9225);
DISPLAY INVISIBLE (125 9225);
FORCEADD DNS..2
(-3150 9775);
PAINT RED (-3150 9775);
FORCEPROP 2 LAST CDS_LIB mstr_misc
J 0
(-3150 9775);
PAINT MONO (-3150 9775);
DISPLAY INVISIBLE (-3150 9775);
FORCEPROP 1 LAST COMMENT_BODY TRUE
R 1
J 0
(-3075 9550);
DISPLAY 0.872340 (-3075 9550);
PAINT GREEN (-3075 9550);
DISPLAY INVISIBLE (-3075 9550);
FORCEADD DNS..2
(-5100 10700);
PAINT RED (-5100 10700);
FORCEPROP 2 LAST CDS_LIB mstr_misc
J 0
(-5100 10700);
PAINT MONO (-5100 10700);
DISPLAY INVISIBLE (-5100 10700);
FORCEPROP 1 LAST COMMENT_BODY TRUE
R 1
J 0
(-5025 10475);
DISPLAY 0.872340 (-5025 10475);
PAINT GREEN (-5025 10475);
DISPLAY INVISIBLE (-5025 10475);
FORCEADD DESIGN_NOTE..1
(2400 8375);
FORCEPROP 0 LAST S5 CLK 100M:
J 0
(2200 8250);
DISPLAY 0.808511 (2200 8250);
PAINT SKYBLUE (2200 8250);
FORCEPROP 0 LAST S4 PORT 0: CLK BUF- DB2000
J 0
(2200 8175);
DISPLAY 0.808511 (2200 8175);
PAINT SKYBLUE (2200 8175);
FORCEPROP 0 LAST S7 CLK 25M:
J 0
(2200 8100);
DISPLAY 0.808511 (2200 8100);
PAINT SKYBLUE (2200 8100);
FORCEPROP 0 LAST S8 PORT 0:CPU0
J 0
(2200 8025);
DISPLAY 0.808511 (2200 8025);
PAINT SKYBLUE (2200 8025);
FORCEPROP 0 LAST S9 PORT 1:CPU1
J 0
(2200 7950);
DISPLAY 0.808511 (2200 7950);
PAINT SKYBLUE (2200 7950);
FORCEPROP 0 LAST S10 PORT 2:ISCLK
J 0
(2200 7875);
DISPLAY 0.808511 (2200 7875);
PAINT SKYBLUE (2200 7875);
FORCEPROP 1 LAST COMMENT_BODY TRUE
J 0
(2425 8475);
DISPLAY 0.978723 (2425 8475);
DISPLAY INVISIBLE (2425 8475);
FORCEPROP 2 LAST CDS_LIB logical_power
J 0
(2400 8375);
DISPLAY INVISIBLE (2400 8375);
WIRE 16 -1 (-3175 7075)(-3175 6925);
WIRE 16 -1 (-1325 8425)(-1325 8500);
WIRE 16 -1 (-1325 8425)(-1325 8375);
WIRE 16 -1 (-1100 8425)(-1325 8425);
WIRE 16 -1 (-2175 8750)(-2175 8225);
WIRE 16 -1 (-3475 9200)(-3475 7775);
WIRE 16 -1 (-1725 8625)(-1725 8275);
WIRE 16 -1 (-3050 9050)(-3050 7875);
WIRE 16 -1 (-5625 11000)(-5625 11075);
WIRE 16 -1 (-5350 11000)(-5625 11000);
WIRE 16 -1 (-5625 10825)(-5625 11000);
WIRE 16 -1 (-2625 8900)(-2625 8125);
WIRE 16 -1 (-4575 6850)(-4575 6925);
WIRE 16 -1 (-5625 9450)(-5625 9575);
WIRE 16 -1 (675 6125)(675 5875);
WIRE 16 -1 (675 6125)(675 6175);
WIRE 16 -1 (675 6125)(500 6125);
WIRE 16 -1 (-5175 5175)(-5175 5275);
WIRE 16 -1 (-4275 5175)(-4275 5275);
WIRE 16 -1 (-1950 5675)(-1950 5600);
WIRE 16 2175 (-5850 5075)(-3675 5075);
WIRE 16 2175 (-3675 5675)(-3675 5075);
WIRE 16 2175 (-5850 5675)(-5850 5075);
WIRE 16 2175 (-5850 5675)(-3675 5675);
WIRE 16 -1 (-4350 5600)(-4450 5600);
WIRE 16 -1 (-4350 5600)(-4350 5275);
WIRE 16 -1 (-4350 5275)(-4275 5275);
WIRE 16 -1 (-4275 5275)(-4275 5375);
WIRE 16 -1 (-5175 5275)(-5175 5375);
WIRE 16 -1 (-5100 5275)(-5175 5275);
WIRE 16 -1 (-5100 5600)(-5100 5275);
WIRE 16 -1 (-5000 5600)(-5100 5600);
WIRE 16 -1 (-4275 5575)(-4275 5800);
WIRE 16 -1 (-4275 5800)(-4450 5800);
WIRE 16 -1 (-4275 5800)(-4275 6225);
WIRE 16 -1 (-1100 6225)(-4275 6225);
FORCEPROP 2 LAST SIG_NAME XTAL_CLK_GEN1_25M_X2
J 0
(-1885 6235);
DISPLAY 0.553191 (-1885 6235);
PAINT WHITE (-1885 6235);
WIRE 16 -1 (-5175 6275)(-4250 6275);
FORCEPROP 2 LAST SIG_NAME XTAL_CLK_GEN1_25M_X1_R
J 0
(-4985 6285);
DISPLAY 0.553191 (-4985 6285);
PAINT WHITE (-4985 6285);
WIRE 16 -1 (-5175 5800)(-5000 5800);
WIRE 16 -1 (-5175 6275)(-5175 5800);
WIRE 16 -1 (-5175 5575)(-5175 5800);
WIRE 16 -1 (-1100 7125)(-2050 7125);
FORCEPROP 2 LAST SIG_NAME CLK_CK440_SMB_ADDR1
J 0
(-1885 7135);
DISPLAY 0.553191 (-1885 7135);
PAINT WHITE (-1885 7135);
WIRE 16 -1 (-1100 7275)(-2050 7275);
FORCEPROP 2 LAST SIG_NAME SMB_HOST_CLK_3V3AUX_SDA
J 0
(-1885 7285);
DISPLAY 0.553191 (-1885 7285);
PAINT WHITE (-1885 7285);
WIRE 16 -1 (-1100 7325)(-2050 7325);
FORCEPROP 2 LAST SIG_NAME SMB_HOST_CLK_3V3AUX_SCL
J 0
(-1885 7335);
DISPLAY 0.553191 (-1885 7335);
PAINT WHITE (-1885 7335);
WIRE 16 -1 (-1100 7425)(-2050 7425);
FORCEPROP 2 LAST SIG_NAME PU_CK440_SHFT_LD_N
J 0
(-1885 7435);
DISPLAY 0.553191 (-1885 7435);
PAINT WHITE (-1885 7435);
WIRE 16 -1 (-1100 7175)(-2050 7175);
FORCEPROP 2 LAST SIG_NAME CLK_CK440_SMB_ADDR0
J 0
(-1885 7185);
DISPLAY 0.553191 (-1885 7185);
PAINT WHITE (-1885 7185);
WIRE 16 -1 (-1100 7075)(-2050 7075);
FORCEPROP 2 LAST SIG_NAME FM_CLK_CK440_SS_EN
J 0
(-1885 7085);
DISPLAY 0.553191 (-1885 7085);
PAINT WHITE (-1885 7085);
WIRE 16 -1 (-2050 6975)(-1100 6975);
FORCEPROP 2 LAST SIG_NAME FM_CLK_GEN1_OE0_N
J 0
(-1885 6985);
DISPLAY 0.553191 (-1885 6985);
PAINT WHITE (-1885 6985);
WIRE 16 -1 (-1100 6925)(-2550 6925);
FORCEPROP 2 LAST SIG_NAME CK440Q_OE_1
J 0
(-1885 6935);
DISPLAY 0.553191 (-1885 6935);
PAINT WHITE (-1885 6935);
WIRE 16 -1 (-1100 6775)(-2550 6775);
FORCEPROP 2 LAST SIG_NAME CK440Q_OE_4
J 0
(-1885 6785);
DISPLAY 0.553191 (-1885 6785);
PAINT WHITE (-1885 6785);
WIRE 16 -1 (1625 7775)(500 7775);
FORCEPROP 2 LAST SIG_NAME NC_CLK_CK440_100M6_DN
J 0
(665 7785);
DISPLAY 0.553191 (665 7785);
PAINT WHITE (665 7785);
WIRE 16 -1 (-1100 6275)(-4050 6275);
FORCEPROP 0 LAST CDS_PHYS_NET_NAME FM_PLD_CLK_25M_EN
J 0
(-3910 6311);
PAINT MONO (-3910 6311);
DISPLAY INVISIBLE (-3910 6311);
FORCEPROP 2 LAST SIG_NAME XTAL_CLK_GEN1_25M_X1
J 0
(-1885 6285);
DISPLAY 0.553191 (-1885 6285);
PAINT WHITE (-1885 6285);
WIRE 16 -1 (-1100 6575)(-4575 6575);
FORCEPROP 2 LAST SIG_NAME PU_CLK_PFT_LOST_N
J 0
(-1885 6585);
DISPLAY 0.553191 (-1885 6585);
PAINT WHITE (-1885 6585);
WIRE 16 -1 (-4575 6650)(-4575 6575);
WIRE 16 -1 (-2225 6125)(-1950 6125);
WIRE 16 -1 (-1950 5875)(-1950 6125);
WIRE 16 -1 (-1950 6125)(-1275 6125);
FORCEPROP 2 LAST SIG_NAME FM_CK440Q_DEV_25M_EN
J 0
(-1885 6135);
DISPLAY 0.553191 (-1885 6135);
PAINT WHITE (-1885 6135);
WIRE 16 -1 (-1275 6125)(-1100 6125);
WIRE 16 -1 (-1275 6125)(-1275 6025);
WIRE 16 -1 (-3275 6025)(-1275 6025);
WIRE 16 -1 (-2425 6125)(-3275 6125);
FORCEPROP 0 LAST CDS_PHYS_NET_NAME FM_PLD_CLK_25M_EN
J 0
(-3135 6161);
PAINT MONO (-3135 6161);
DISPLAY INVISIBLE (-3135 6161);
FORCEPROP 2 LAST SIG_NAME FM_PLD_CLK_25M_EN
J 0
(-3135 6135);
DISPLAY 0.553191 (-3135 6135);
PAINT WHITE (-3135 6135);
WIRE 16 -1 (-3150 9700)(-3150 9575);
WIRE 16 -1 (-3375 9700)(-3375 9575);
WIRE 16 -1 (-3150 9575)(-3375 9575);
WIRE 16 -1 (-3625 9700)(-3625 9575);
WIRE 16 -1 (-3625 9575)(-3375 9575);
WIRE 16 -1 (-3875 9700)(-3875 9575);
WIRE 16 -1 (-3875 9575)(-3625 9575);
WIRE 16 -1 (-5625 9575)(-5625 9700);
WIRE 16 -1 (-4125 9700)(-4125 9575);
WIRE 16 -1 (-3875 9575)(-4125 9575);
WIRE 16 -1 (-4400 9700)(-4400 9575);
WIRE 16 -1 (-4125 9575)(-4400 9575);
WIRE 16 -1 (-5350 9575)(-5625 9575);
WIRE 16 -1 (-5350 9700)(-5350 9575);
WIRE 16 -1 (-5100 9575)(-5350 9575);
WIRE 16 -1 (-5100 9700)(-5100 9575);
WIRE 16 -1 (-4675 9700)(-4675 9575);
WIRE 16 -1 (-4400 9575)(-4675 9575);
WIRE 16 -1 (-4675 9575)(-5100 9575);
WIRE 16 -1 (1625 6525)(500 6525);
FORCEPROP 2 LAST SIG_NAME NC_CLK_CK440_MXCK8_DN
J 0
(665 6535);
DISPLAY 0.553191 (665 6535);
PAINT WHITE (665 6535);
WIRE 16 -1 (1575 6425)(500 6425);
FORCEPROP 2 LAST SIG_NAME TP_CLK_CK440_PFT_OUT_DP
J 0
(665 6435);
DISPLAY 0.553191 (665 6435);
PAINT WHITE (665 6435);
WIRE 16 -1 (1575 6375)(500 6375);
FORCEPROP 2 LAST SIG_NAME TP_CLK_CK440_PFT_OUT_DN
J 0
(665 6385);
DISPLAY 0.553191 (665 6385);
PAINT WHITE (665 6385);
WIRE 16 -1 (1625 6675)(500 6675);
FORCEPROP 2 LAST SIG_NAME NC_CLK_CK440_MXCK7_DP
J 0
(665 6685);
DISPLAY 0.553191 (665 6685);
PAINT WHITE (665 6685);
WIRE 16 -1 (1625 6725)(500 6725);
FORCEPROP 2 LAST SIG_NAME NC_CLK_CK440_MXCK6_DN
J 0
(665 6735);
DISPLAY 0.553191 (665 6735);
PAINT WHITE (665 6735);
WIRE 16 -1 (1625 6875)(500 6875);
FORCEPROP 2 LAST SIG_NAME NC_CLK_CK440_MXCK5_DP
J 0
(665 6885);
DISPLAY 0.553191 (665 6885);
PAINT WHITE (665 6885);
WIRE 16 -1 (1625 6825)(500 6825);
FORCEPROP 2 LAST SIG_NAME NC_CLK_CK440_MXCK5_DN
J 0
(665 6835);
DISPLAY 0.553191 (665 6835);
PAINT WHITE (665 6835);
WIRE 16 -1 (1625 6925)(500 6925);
FORCEPROP 2 LAST SIG_NAME NC_CLK_CK440_MXCK4_DN
J 0
(665 6935);
DISPLAY 0.553191 (665 6935);
PAINT WHITE (665 6935);
WIRE 16 -1 (1625 6975)(500 6975);
FORCEPROP 2 LAST SIG_NAME NC_CLK_CK440_MXCK4_DP
J 0
(665 6985);
DISPLAY 0.553191 (665 6985);
PAINT WHITE (665 6985);
WIRE 16 -1 (1625 7025)(500 7025);
FORCEPROP 2 LAST SIG_NAME NC_CLK_CK440_MXCK3_DN
J 0
(665 7035);
DISPLAY 0.553191 (665 7035);
PAINT WHITE (665 7035);
WIRE 16 -1 (1625 7075)(500 7075);
FORCEPROP 2 LAST SIG_NAME NC_CLK_CK440_MXCK3_DP
J 0
(665 7085);
DISPLAY 0.553191 (665 7085);
PAINT WHITE (665 7085);
WIRE 16 -1 (1625 7125)(500 7125);
FORCEPROP 2 LAST SIG_NAME CLK_100M_CK440_PCH_EXTCLK_R_DN
J 0
(665 7135);
DISPLAY 0.553191 (665 7135);
PAINT WHITE (665 7135);
WIRE 16 -1 (1625 6775)(500 6775);
FORCEPROP 2 LAST SIG_NAME NC_CLK_CK440_MXCK6_DP
J 0
(665 6785);
DISPLAY 0.553191 (665 6785);
PAINT WHITE (665 6785);
WIRE 16 -1 (1625 6625)(500 6625);
FORCEPROP 2 LAST SIG_NAME NC_CLK_CK440_MXCK7_DN
J 0
(665 6635);
DISPLAY 0.553191 (665 6635);
PAINT WHITE (665 6635);
WIRE 16 -1 (1625 6575)(500 6575);
FORCEPROP 2 LAST SIG_NAME NC_CLK_CK440_MXCK8_DP
J 0
(665 6585);
DISPLAY 0.553191 (665 6585);
PAINT WHITE (665 6585);
WIRE 16 -1 (1625 7175)(500 7175);
FORCEPROP 2 LAST SIG_NAME CLK_100M_CK440_PCH_EXTCLK_R_DP
J 0
(665 7185);
DISPLAY 0.553191 (665 7185);
PAINT WHITE (665 7185);
WIRE 16 -1 (1625 7325)(500 7325);
FORCEPROP 2 LAST SIG_NAME NC_CLK_CK440_MXCK0_DN
J 0
(665 7335);
DISPLAY 0.553191 (665 7335);
PAINT WHITE (665 7335);
WIRE 16 -1 (1625 7375)(500 7375);
FORCEPROP 2 LAST SIG_NAME NC_CLK_CK440_MXCK0_DP
J 0
(665 7385);
DISPLAY 0.553191 (665 7385);
PAINT WHITE (665 7385);
WIRE 16 -1 (1625 7475)(500 7475);
FORCEPROP 2 LAST SIG_NAME CLK_25M_CK440_ISCLK_REF_DN
J 0
(665 7485);
DISPLAY 0.553191 (665 7485);
PAINT WHITE (665 7485);
WIRE 16 -1 (1625 7275)(500 7275);
FORCEPROP 2 LAST SIG_NAME NC_CLK_CK440_MXCK1_DP
J 0
(665 7285);
DISPLAY 0.553191 (665 7285);
PAINT WHITE (665 7285);
WIRE 16 -1 (1625 7225)(500 7225);
FORCEPROP 2 LAST SIG_NAME NC_CLK_CK440_MXCK1_DN
J 0
(665 7235);
DISPLAY 0.553191 (665 7235);
PAINT WHITE (665 7235);
WIRE 16 -1 (1625 7525)(500 7525);
FORCEPROP 2 LAST SIG_NAME CLK_25M_CK440_ISCLK_REF_DP
J 0
(665 7535);
DISPLAY 0.553191 (665 7535);
PAINT WHITE (665 7535);
WIRE 16 -1 (1625 7575)(500 7575);
FORCEPROP 2 LAST SIG_NAME CLK_25M_CK440_CPU1_DN
J 0
(665 7585);
DISPLAY 0.553191 (665 7585);
PAINT WHITE (665 7585);
WIRE 16 -1 (1625 7625)(500 7625);
FORCEPROP 2 LAST SIG_NAME CLK_25M_CK440_CPU1_DP
J 0
(665 7635);
DISPLAY 0.553191 (665 7635);
PAINT WHITE (665 7635);
WIRE 16 -1 (1625 7675)(500 7675);
FORCEPROP 2 LAST SIG_NAME CLK_25M_CK440_CPU0_DN
J 0
(665 7685);
DISPLAY 0.553191 (665 7685);
PAINT WHITE (665 7685);
WIRE 16 -1 (1625 7725)(500 7725);
FORCEPROP 2 LAST SIG_NAME CLK_25M_CK440_CPU0_DP
J 0
(665 7735);
DISPLAY 0.553191 (665 7735);
PAINT WHITE (665 7735);
WIRE 16 -1 (1625 7825)(500 7825);
FORCEPROP 2 LAST SIG_NAME NC_CLK_CK440_100M6_DP
J 0
(665 7835);
DISPLAY 0.553191 (665 7835);
PAINT WHITE (665 7835);
WIRE 16 -1 (1625 7875)(500 7875);
FORCEPROP 2 LAST SIG_NAME NC_CLK_CK440_100M5_DN
J 0
(665 7885);
DISPLAY 0.553191 (665 7885);
PAINT WHITE (665 7885);
WIRE 16 -1 (1625 7925)(500 7925);
FORCEPROP 2 LAST SIG_NAME NC_CLK_CK440_100M5_DP
J 0
(665 7935);
DISPLAY 0.553191 (665 7935);
PAINT WHITE (665 7935);
WIRE 16 -1 (1625 7975)(500 7975);
FORCEPROP 2 LAST SIG_NAME NC_CLK_CK440_100M4_DN
J 0
(665 7985);
DISPLAY 0.553191 (665 7985);
PAINT WHITE (665 7985);
WIRE 16 -1 (-2175 8225)(-1100 8225);
WIRE 16 -1 (-1100 7675)(-2050 7675);
FORCEPROP 2 LAST SIG_NAME FM_CK440_MXCK_25M_100M
J 0
(-1885 7685);
DISPLAY 0.553191 (-1885 7685);
PAINT WHITE (-1885 7685);
WIRE 16 -1 (-3475 7775)(-1100 7775);
WIRE 16 -1 (-4400 10225)(-4400 9900);
WIRE 16 -1 (-4400 10625)(-4400 10225);
WIRE 16 -1 (-2350 10225)(-4400 10225);
FORCEPROP 2 LAST SIG_NAME FM_PLD_CLKS_DEV_EN
J 0
(-3010 10235);
DISPLAY 0.553191 (-3010 10235);
PAINT WHITE (-3010 10235);
WIRE 16 -1 (-1100 6375)(-2050 6375);
FORCEPROP 2 LAST SIG_NAME FM_PLD_CLKS_DEV_EN
J 0
(-1885 6385);
DISPLAY 0.553191 (-1885 6385);
PAINT WHITE (-1885 6385);
WIRE 16 -1 (-1100 6475)(-2050 6475);
FORCEPROP 2 LAST SIG_NAME TP_CLK_PFT_IN_DN
J 0
(-1885 6485);
DISPLAY 0.553191 (-1885 6485);
PAINT WHITE (-1885 6485);
WIRE 16 -1 (-1100 6675)(-2550 6675);
FORCEPROP 2 LAST SIG_NAME CK440Q_OE_6
J 0
(-1885 6685);
DISPLAY 0.510638 (-1885 6685);
PAINT WHITE (-1885 6685);
WIRE 16 -1 (-1100 6825)(-2550 6825);
FORCEPROP 2 LAST SIG_NAME CK440Q_OE_3
J 0
(-1885 6835);
DISPLAY 0.553191 (-1885 6835);
PAINT WHITE (-1885 6835);
WIRE 16 -1 (-1100 6725)(-2550 6725);
FORCEPROP 2 LAST SIG_NAME CK440Q_OE_5
J 0
(-1885 6735);
DISPLAY 0.510638 (-1885 6735);
PAINT WHITE (-1885 6735);
WIRE 16 -1 (-1100 6525)(-2050 6525);
FORCEPROP 2 LAST SIG_NAME TP_CLK_PFT_IN_DP
J 0
(-1885 6535);
DISPLAY 0.553191 (-1885 6535);
PAINT WHITE (-1885 6535);
WIRE 16 -1 (-1100 6875)(-2550 6875);
FORCEPROP 2 LAST SIG_NAME CK440Q_OE_2
J 0
(-1885 6885);
DISPLAY 0.553191 (-1885 6885);
PAINT WHITE (-1885 6885);
WIRE 16 -1 (-1100 7475)(-2050 7475);
FORCEPROP 2 LAST SIG_NAME TP_CK440_SBI_DATA_OUT
J 0
(-1885 7485);
DISPLAY 0.553191 (-1885 7485);
PAINT WHITE (-1885 7485);
WIRE 16 -1 (-3050 7875)(-1100 7875);
WIRE 16 -1 (-1100 8125)(-2625 8125);
WIRE 16 -1 (-2625 8125)(-2625 8075);
WIRE 16 -1 (-2625 8075)(-1100 8075);
WIRE 16 -1 (-2625 8075)(-2625 8025);
WIRE 16 -1 (-1100 8025)(-2625 8025);
WIRE 16 -1 (-2625 8025)(-2625 7975);
WIRE 16 -1 (-2625 7975)(-1100 7975);
WIRE 16 -1 (-5625 10025)(-5625 9900);
WIRE 16 -1 (-5625 10625)(-5625 10025);
WIRE 16 -1 (-2350 10025)(-5625 10025);
FORCEPROP 2 LAST SIG_NAME CLK_CK440_SMB_ADDR1
J 0
(-3010 10035);
DISPLAY 0.553191 (-3010 10035);
PAINT WHITE (-3010 10035);
WIRE 16 -1 (-5350 10075)(-5350 9900);
WIRE 16 -1 (-5350 10625)(-5350 10075);
WIRE 16 -1 (-5350 10075)(-2350 10075);
FORCEPROP 2 LAST SIG_NAME CLK_CK440_SMB_ADDR0
J 0
(-3010 10085);
DISPLAY 0.553191 (-3010 10085);
PAINT WHITE (-3010 10085);
WIRE 16 -1 (-5100 10125)(-5100 9900);
WIRE 16 -1 (-5100 10625)(-5100 10125);
WIRE 16 -1 (-5100 10125)(-2350 10125);
FORCEPROP 2 LAST SIG_NAME FM_CK440_MXCK_25M_100M
J 0
(-3010 10135);
DISPLAY 0.553191 (-3010 10135);
PAINT WHITE (-3010 10135);
WIRE 16 -1 (675 6175)(500 6175);
WIRE 16 -1 (675 6275)(500 6275);
WIRE 16 -1 (675 6225)(500 6225);
WIRE 16 -1 (675 6175)(675 6225);
WIRE 16 -1 (675 6225)(675 6275);
WIRE 16 2175 (-3375 7025)(-3000 7025);
WIRE 16 2175 (-3000 7350)(-3000 7025);
WIRE 16 2175 (-3375 7350)(-3375 7025);
WIRE 16 2175 (-3375 7350)(-3000 7350);
WIRE 16 -1 (-1100 7575)(-2050 7575);
FORCEPROP 2 LAST SIG_NAME PD_CK440_SBI_CLK
J 0
(-1885 7585);
DISPLAY 0.553191 (-1885 7585);
PAINT WHITE (-1885 7585);
WIRE 16 -1 (1625 8025)(500 8025);
FORCEPROP 2 LAST SIG_NAME NC_CLK_CK440_100M4_DP
J 0
(665 8035);
DISPLAY 0.553191 (665 8035);
PAINT WHITE (665 8035);
WIRE 16 -1 (1625 8075)(500 8075);
FORCEPROP 2 LAST SIG_NAME NC_CLK_CK440_100M3_DN
J 0
(665 8085);
DISPLAY 0.553191 (665 8085);
PAINT WHITE (665 8085);
WIRE 16 -1 (1625 8125)(500 8125);
FORCEPROP 2 LAST SIG_NAME NC_CLK_CK440_100M3_DP
J 0
(665 8135);
DISPLAY 0.553191 (665 8135);
PAINT WHITE (665 8135);
WIRE 16 -1 (1625 8175)(500 8175);
FORCEPROP 2 LAST SIG_NAME NC_CLK_CK440_100M2_DN
J 0
(665 8185);
DISPLAY 0.553191 (665 8185);
PAINT WHITE (665 8185);
WIRE 16 -1 (1625 8225)(500 8225);
FORCEPROP 2 LAST SIG_NAME NC_CLK_CK440_100M2_DP
J 0
(665 8235);
DISPLAY 0.553191 (665 8235);
PAINT WHITE (665 8235);
WIRE 16 -1 (1625 8275)(500 8275);
FORCEPROP 2 LAST SIG_NAME NC_CLK_CK440_100M1_DN
J 0
(665 8285);
DISPLAY 0.553191 (665 8285);
PAINT WHITE (665 8285);
WIRE 16 -1 (1625 8325)(500 8325);
FORCEPROP 2 LAST SIG_NAME NC_CLK_CK440_100M1_DP
J 0
(665 8335);
DISPLAY 0.553191 (665 8335);
PAINT WHITE (665 8335);
WIRE 16 -1 (1625 8375)(500 8375);
FORCEPROP 2 LAST SIG_NAME CLK_100M_DB2000_DN
J 0
(665 8385);
DISPLAY 0.553191 (665 8385);
PAINT WHITE (665 8385);
WIRE 16 -1 (-1725 8275)(-1100 8275);
WIRE 16 -1 (-2750 6925)(-3175 6925);
WIRE 16 -1 (-3175 6925)(-3175 6875);
WIRE 16 -1 (-2750 6875)(-3175 6875);
WIRE 16 -1 (-3175 6875)(-3175 6825);
WIRE 16 -1 (-2750 6825)(-3175 6825);
WIRE 16 -1 (-3175 6825)(-3175 6775);
WIRE 16 -1 (-2750 6775)(-3175 6775);
WIRE 16 -1 (-3175 6775)(-3175 6725);
WIRE 16 -1 (-2750 6725)(-3175 6725);
WIRE 16 -1 (-3175 6725)(-3175 6675);
WIRE 16 -1 (-3175 6675)(-2750 6675);
WIRE 16 -1 (-525 10475)(-1175 10475);
FORCEPROP 2 LAST SIG_NAME NC_CK440_B39
J 0
(-1060 10485);
DISPLAY 0.553191 (-1060 10485);
PAINT WHITE (-1060 10485);
WIRE 16 -1 (-525 10525)(-1175 10525);
FORCEPROP 2 LAST SIG_NAME NC_CK440_B41
J 0
(-1060 10535);
DISPLAY 0.553191 (-1060 10535);
PAINT WHITE (-1060 10535);
WIRE 16 -1 (-525 10575)(-1175 10575);
FORCEPROP 2 LAST SIG_NAME NC_CK440_B44
J 0
(-1060 10585);
DISPLAY 0.553191 (-1060 10585);
PAINT WHITE (-1060 10585);
WIRE 16 -1 (-3150 10825)(-3150 11000);
WIRE 16 -1 (-3625 10825)(-3625 11000);
WIRE 16 -1 (-3625 11000)(-3150 11000);
WIRE 16 -1 (-4400 10825)(-4400 11000);
WIRE 16 -1 (-4400 11000)(-3625 11000);
WIRE 16 -1 (-4675 10825)(-4675 11000);
WIRE 16 -1 (-4400 11000)(-4675 11000);
WIRE 16 -1 (-5100 11000)(-5100 10825);
WIRE 16 -1 (-5100 11000)(-4675 11000);
WIRE 16 -1 (-5100 11000)(-5350 11000);
WIRE 16 -1 (-5350 10825)(-5350 11000);
WIRE 16 -1 (-1100 7525)(-2050 7525);
FORCEPROP 2 LAST SIG_NAME PD_CK440_SBI_DATA_IN
J 0
(-1885 7535);
DISPLAY 0.553191 (-1885 7535);
PAINT WHITE (-1885 7535);
WIRE 16 -1 (-3150 9900)(-3150 10475);
WIRE 16 -1 (-2350 10475)(-3150 10475);
FORCEPROP 2 LAST SIG_NAME FM_CK440Q_DEV_25M_EN
J 0
(-3010 10485);
DISPLAY 0.553191 (-3010 10485);
PAINT WHITE (-3010 10485);
WIRE 16 -1 (-3150 10625)(-3150 10475);
WIRE 16 -1 (-3625 10375)(-3625 9900);
WIRE 16 -1 (-3625 10375)(-3625 10625);
WIRE 16 -1 (-3625 10375)(-2350 10375);
FORCEPROP 2 LAST SIG_NAME FM_CLK_CK440_SS_EN
J 0
(-3010 10385);
DISPLAY 0.553191 (-3010 10385);
PAINT WHITE (-3010 10385);
WIRE 16 -1 (-4675 10175)(-4675 9900);
WIRE 16 -1 (-4675 10625)(-4675 10175);
WIRE 16 -1 (-4675 10175)(-2350 10175);
FORCEPROP 2 LAST SIG_NAME PU_CK440_SHFT_LD_N
J 0
(-3010 10185);
DISPLAY 0.553191 (-3010 10185);
PAINT WHITE (-3010 10185);
WIRE 16 -1 (-4125 10275)(-4125 9900);
WIRE 16 -1 (-4125 10275)(-2350 10275);
FORCEPROP 2 LAST SIG_NAME PD_CK440_SBI_CLK
J 0
(-3010 10285);
DISPLAY 0.553191 (-3010 10285);
PAINT WHITE (-3010 10285);
WIRE 16 -1 (-3375 9900)(-3375 10425);
WIRE 16 -1 (-2350 10425)(-3375 10425);
FORCEPROP 2 LAST SIG_NAME FM_CLK_GEN1_OE0_N
J 0
(-3010 10435);
DISPLAY 0.553191 (-3010 10435);
PAINT WHITE (-3010 10435);
WIRE 16 -1 (-3875 10325)(-3875 9900);
WIRE 16 -1 (-3875 10325)(-2350 10325);
FORCEPROP 2 LAST SIG_NAME PD_CK440_SBI_DATA_IN
J 0
(-3010 10335);
DISPLAY 0.553191 (-3010 10335);
PAINT WHITE (-3010 10335);
WIRE 16 -1 (-1100 8375)(-1325 8375);
WIRE 16 -1 (1625 8425)(500 8425);
FORCEPROP 2 LAST SIG_NAME CLK_100M_DB2000_DP
J 0
(665 8435);
DISPLAY 0.553191 (665 8435);
PAINT WHITE (665 8435);
WIRE 16 -1 (-525 10425)(-1175 10425);
FORCEPROP 2 LAST SIG_NAME NC_CK440_B37
J 0
(-1060 10435);
DISPLAY 0.553191 (-1060 10435);
PAINT WHITE (-1060 10435);
WIRE 16 -1 (-525 10375)(-1175 10375);
FORCEPROP 2 LAST SIG_NAME NC_CK440_B36
J 0
(-1060 10385);
DISPLAY 0.553191 (-1060 10385);
PAINT WHITE (-1060 10385);
WIRE 16 -1 (-525 10325)(-1175 10325);
FORCEPROP 2 LAST SIG_NAME NC_CK440_B34
J 0
(-1060 10335);
DISPLAY 0.553191 (-1060 10335);
PAINT WHITE (-1060 10335);
WIRE 16 -1 (-525 10275)(-1175 10275);
FORCEPROP 2 LAST SIG_NAME NC_CK440_B33
J 0
(-1060 10285);
DISPLAY 0.553191 (-1060 10285);
PAINT WHITE (-1060 10285);
WIRE 16 -1 (-525 10225)(-1175 10225);
FORCEPROP 2 LAST SIG_NAME NC_CK440_B31
J 0
(-1060 10235);
DISPLAY 0.553191 (-1060 10235);
PAINT WHITE (-1060 10235);
WIRE 16 -1 (-525 10175)(-1175 10175);
FORCEPROP 2 LAST SIG_NAME NC_CK440_B30
J 0
(-1060 10185);
DISPLAY 0.553191 (-1060 10185);
PAINT WHITE (-1060 10185);
WIRE 16 -1 (-525 10125)(-1175 10125);
FORCEPROP 2 LAST SIG_NAME NC_CK440_B28
J 0
(-1060 10135);
DISPLAY 0.553191 (-1060 10135);
PAINT WHITE (-1060 10135);
WIRE 16 -1 (-525 10075)(-1175 10075);
FORCEPROP 2 LAST SIG_NAME NC_CK440_B26
J 0
(-1060 10085);
DISPLAY 0.553191 (-1060 10085);
PAINT WHITE (-1060 10085);
WIRE 16 -1 (-525 10025)(-1175 10025);
FORCEPROP 2 LAST SIG_NAME NC_CK440_B25
J 0
(-1060 10035);
DISPLAY 0.553191 (-1060 10035);
PAINT WHITE (-1060 10035);
WIRE 16 -1 (1125 10575)(475 10575);
FORCEPROP 2 LAST SIG_NAME NC_CK440_B24
J 0
(690 10585);
DISPLAY 0.553191 (690 10585);
PAINT WHITE (690 10585);
WIRE 16 -1 (1125 10525)(475 10525);
FORCEPROP 2 LAST SIG_NAME NC_CK440_A15
J 0
(690 10535);
DISPLAY 0.553191 (690 10535);
PAINT WHITE (690 10535);
WIRE 16 -1 (1125 10475)(475 10475);
FORCEPROP 2 LAST SIG_NAME NC_CK440_B2
J 0
(690 10485);
DISPLAY 0.553191 (690 10485);
PAINT WHITE (690 10485);
WIRE 16 -1 (1125 10425)(475 10425);
FORCEPROP 2 LAST SIG_NAME NC_CK440_B3
J 0
(690 10435);
DISPLAY 0.553191 (690 10435);
PAINT WHITE (690 10435);
WIRE 16 -1 (1125 10375)(475 10375);
FORCEPROP 2 LAST SIG_NAME NC_CK440_B5
J 0
(690 10385);
DISPLAY 0.553191 (690 10385);
PAINT WHITE (690 10385);
WIRE 16 -1 (1125 10325)(475 10325);
FORCEPROP 2 LAST SIG_NAME NC_CK440_B7
J 0
(690 10335);
DISPLAY 0.553191 (690 10335);
PAINT WHITE (690 10335);
WIRE 16 -1 (1125 10275)(475 10275);
FORCEPROP 2 LAST SIG_NAME NC_CK440_B13
J 0
(690 10285);
DISPLAY 0.553191 (690 10285);
PAINT WHITE (690 10285);
WIRE 16 -1 (1125 10225)(475 10225);
FORCEPROP 2 LAST SIG_NAME NC_CK440_B16
J 0
(690 10235);
DISPLAY 0.553191 (690 10235);
PAINT WHITE (690 10235);
WIRE 16 -1 (1125 10175)(475 10175);
FORCEPROP 2 LAST SIG_NAME NC_CK440_B18
J 0
(690 10185);
DISPLAY 0.553191 (690 10185);
PAINT WHITE (690 10185);
WIRE 16 -1 (1125 10125)(475 10125);
FORCEPROP 2 LAST SIG_NAME NC_CK440_B20
J 0
(690 10135);
DISPLAY 0.553191 (690 10135);
PAINT WHITE (690 10135);
WIRE 16 -1 (1125 10075)(475 10075);
FORCEPROP 2 LAST SIG_NAME NC_CK440_B22
J 0
(690 10085);
DISPLAY 0.553191 (690 10085);
PAINT WHITE (690 10085);
DOT 1 (-3625 9575);
DOT 1 (-3375 9575);
DOT 1 (-1275 6125);
DOT 1 (-3175 6775);
DOT 1 (-3175 6925);
DOT 1 (-3175 6875);
DOT 1 (-3175 6825);
DOT 1 (-3175 6725);
DOT 1 (-2625 8025);
DOT 1 (-5625 9575);
DOT 1 (-5350 9575);
DOT 1 (-5625 10025);
DOT 1 (-5350 10075);
DOT 1 (-5100 9575);
DOT 1 (-4400 9575);
DOT 1 (-5625 11000);
DOT 1 (-5350 11000);
DOT 1 (-5100 10125);
DOT 1 (-5100 11000);
DOT 1 (-4400 10225);
DOT 1 (-4675 10175);
DOT 1 (-4675 11000);
DOT 1 (-4400 11000);
DOT 1 (-3875 9575);
DOT 1 (-4125 9575);
DOT 1 (-3625 11000);
DOT 1 (-2625 8075);
DOT 1 (-2625 8125);
DOT 1 (675 6225);
DOT 1 (675 6125);
DOT 1 (675 6175);
DOT 1 (-4275 5800);
DOT 1 (-1325 8425);
DOT 1 (-3150 10475);
DOT 1 (-3625 10375);
DOT 1 (-1950 6125);
DOT 1 (-4675 9575);
DOT 1 (-5175 5275);
DOT 1 (-5175 5800);
DOT 1 (-4275 5275);
FORCENOTE
20210603 MODIFY FOR GT
(150 9400) 0;
DISPLAY LEFT (150 9400);
DISPLAY 2.510638 (150 9400);
PAINT PINK (150 9400);
FORCENOTE
20211201 PU TO P3V3_AUX
(-3925 7375) 0;
DISPLAY LEFT (-3925 7375);
DISPLAY 1.276596 (-3925 7375);
PAINT PINK (-3925 7375);
FORCENOTE
20220331 CHANGE TO 8.2PF
(-3625 5075) 0;
DISPLAY LEFT (-3625 5075);
DISPLAY 1.276596 (-3625 5075);
PAINT PINK (-3625 5075);
QUIT
